FILE_TYPE = MACRO_DRAWING;
SET COLOR_WIRE YELLOW;
SET COLOR_PROP ORANGE;
SET COLOR_DOT WHITE;
SET COLOR_ARC YELLOW;
SET COLOR_BODY GREEN;
SET COLOR_NOTE PURPLE;
SET PROP_DISPLAY VALUE;
SET PAGE_NUMBER P20;
FORCEADD GENOA_SP5..36
(-4425 3575);
FORCEPROP 1 LAST LOCATION U25
J 0
(-5070 6406);
DISPLAY 0.489362 (-5070 6406);
PAINT SKYBLUE (-5070 6406);
FORCEPROP 0 LAST $SEC 36
J 0
(-5050 6550);
DISPLAY 0.680851 (-5050 6550);
PAINT MONO (-5050 6550);
DISPLAY INVISIBLE (-5050 6550);
FORCEPROP 0 LAST CDS_SEC 36
J 0
(-5050 6550);
DISPLAY 1.021277 (-5050 6550);
DISPLAY INVISIBLE (-5050 6550);
FORCEPROP 0 LASTPIN (-5225 2950) $PN BC5
J 2
(-5235 2960);
DISPLAY 0.489362 (-5235 2960);
PAINT MONO (-5235 2960);
FORCEPROP 0 LASTPIN (-5225 2900) $PN BD6
J 2
(-5235 2910);
DISPLAY 0.489362 (-5235 2910);
PAINT MONO (-5235 2910);
FORCEPROP 0 LASTPIN (-5225 1800) $PN BF6
J 2
(-5235 1810);
DISPLAY 0.489362 (-5235 1810);
PAINT MONO (-5235 1810);
FORCEPROP 0 LASTPIN (-5225 1750) $PN BG5
J 2
(-5235 1760);
DISPLAY 0.489362 (-5235 1760);
PAINT MONO (-5235 1760);
FORCEPROP 0 LASTPIN (-5225 2100) $PN AT7
J 2
(-5235 2110);
DISPLAY 0.489362 (-5235 2110);
PAINT MONO (-5235 2110);
FORCEPROP 0 LASTPIN (-5225 2000) $PN AU7
J 2
(-5235 2010);
DISPLAY 0.489362 (-5235 2010);
PAINT MONO (-5235 2010);
FORCEPROP 0 LASTPIN (-5225 2800) $PN AU5
J 2
(-5235 2810);
DISPLAY 0.489362 (-5235 2810);
PAINT MONO (-5235 2810);
FORCEPROP 0 LASTPIN (-5225 2750) $PN AV7
J 2
(-5235 2760);
DISPLAY 0.489362 (-5235 2760);
PAINT MONO (-5235 2760);
FORCEPROP 0 LASTPIN (-5225 2650) $PN BN7
J 2
(-5235 2660);
DISPLAY 0.489362 (-5235 2660);
PAINT MONO (-5235 2660);
FORCEPROP 0 LASTPIN (-5225 1650) $PN AV6
J 2
(-5235 1660);
DISPLAY 0.489362 (-5235 1660);
PAINT MONO (-5235 1660);
FORCEPROP 0 LASTPIN (-5225 1600) $PN AW7
J 2
(-5235 1610);
DISPLAY 0.489362 (-5235 1610);
PAINT MONO (-5235 1610);
FORCEPROP 0 LASTPIN (-5225 1500) $PN BP7
J 2
(-5235 1510);
DISPLAY 0.489362 (-5235 1510);
PAINT MONO (-5235 1510);
FORCEPROP 0 LASTPIN (-5225 3800) $PN AW5
J 2
(-5235 3810);
DISPLAY 0.489362 (-5235 3810);
PAINT MONO (-5235 3810);
FORCEPROP 0 LASTPIN (-5225 3750) $PN AY6
J 2
(-5235 3760);
DISPLAY 0.489362 (-5235 3760);
PAINT MONO (-5235 3760);
FORCEPROP 0 LASTPIN (-5225 3700) $PN AY7
J 2
(-5235 3710);
DISPLAY 0.489362 (-5235 3710);
PAINT MONO (-5235 3710);
FORCEPROP 0 LASTPIN (-5225 3650) $PN BA7
J 2
(-5235 3660);
DISPLAY 0.489362 (-5235 3660);
PAINT MONO (-5235 3660);
FORCEPROP 0 LASTPIN (-5225 3600) $PN BA5
J 2
(-5235 3610);
DISPLAY 0.489362 (-5235 3610);
PAINT MONO (-5235 3610);
FORCEPROP 0 LASTPIN (-5225 3550) $PN BB6
J 2
(-5235 3560);
DISPLAY 0.489362 (-5235 3560);
PAINT MONO (-5235 3560);
FORCEPROP 0 LASTPIN (-5225 3500) $PN BB7
J 2
(-5235 3510);
DISPLAY 0.489362 (-5235 3510);
PAINT MONO (-5235 3510);
FORCEPROP 0 LASTPIN (-3625 2350) $PN AJ5
J 0
(-3615 2360);
DISPLAY 0.489362 (-3615 2360);
PAINT MONO (-3615 2360);
FORCEPROP 0 LASTPIN (-3625 2300) $PN AK7
J 0
(-3615 2310);
DISPLAY 0.489362 (-3615 2310);
PAINT MONO (-3615 2310);
FORCEPROP 0 LASTPIN (-3625 2250) $PN AK6
J 0
(-3615 2260);
DISPLAY 0.489362 (-3615 2260);
PAINT MONO (-3615 2260);
FORCEPROP 0 LASTPIN (-3625 2200) $PN AL7
J 0
(-3615 2210);
DISPLAY 0.489362 (-3615 2210);
PAINT MONO (-3615 2210);
FORCEPROP 0 LASTPIN (-3625 2150) $PN AN5
J 0
(-3615 2160);
DISPLAY 0.489362 (-3615 2160);
PAINT MONO (-3615 2160);
FORCEPROP 0 LASTPIN (-3625 2100) $PN AP7
J 0
(-3615 2110);
DISPLAY 0.489362 (-3615 2110);
PAINT MONO (-3615 2110);
FORCEPROP 0 LASTPIN (-3625 2050) $PN AP6
J 0
(-3615 2060);
DISPLAY 0.489362 (-3615 2060);
PAINT MONO (-3615 2060);
FORCEPROP 0 LASTPIN (-3625 2000) $PN AR7
J 0
(-3615 2010);
DISPLAY 0.489362 (-3615 2010);
PAINT MONO (-3615 2010);
FORCEPROP 0 LASTPIN (-3625 5950) $PN E5
J 0
(-3615 5960);
DISPLAY 0.489362 (-3615 5960);
PAINT MONO (-3615 5960);
FORCEPROP 0 LASTPIN (-3625 5900) $PN F7
J 0
(-3615 5910);
DISPLAY 0.489362 (-3615 5910);
PAINT MONO (-3615 5910);
FORCEPROP 0 LASTPIN (-3625 5850) $PN F6
J 0
(-3615 5860);
DISPLAY 0.489362 (-3615 5860);
PAINT MONO (-3615 5860);
FORCEPROP 0 LASTPIN (-3625 5800) $PN G7
J 0
(-3615 5810);
DISPLAY 0.489362 (-3615 5810);
PAINT MONO (-3615 5810);
FORCEPROP 0 LASTPIN (-3625 5750) $PN J5
J 0
(-3615 5760);
DISPLAY 0.489362 (-3615 5760);
PAINT MONO (-3615 5760);
FORCEPROP 0 LASTPIN (-3625 5700) $PN K7
J 0
(-3615 5710);
DISPLAY 0.489362 (-3615 5710);
PAINT MONO (-3615 5710);
FORCEPROP 0 LASTPIN (-3625 5650) $PN K6
J 0
(-3615 5660);
DISPLAY 0.489362 (-3615 5660);
PAINT MONO (-3615 5660);
FORCEPROP 0 LASTPIN (-3625 5600) $PN L7
J 0
(-3615 5610);
DISPLAY 0.489362 (-3615 5610);
PAINT MONO (-3615 5610);
FORCEPROP 0 LASTPIN (-3625 5500) $PN L5
J 0
(-3615 5510);
DISPLAY 0.489362 (-3615 5510);
PAINT MONO (-3615 5510);
FORCEPROP 0 LASTPIN (-3625 5450) $PN M7
J 0
(-3615 5460);
DISPLAY 0.489362 (-3615 5460);
PAINT MONO (-3615 5460);
FORCEPROP 0 LASTPIN (-3625 5400) $PN M6
J 0
(-3615 5410);
DISPLAY 0.489362 (-3615 5410);
PAINT MONO (-3615 5410);
FORCEPROP 0 LASTPIN (-3625 5350) $PN N7
J 0
(-3615 5360);
DISPLAY 0.489362 (-3615 5360);
PAINT MONO (-3615 5360);
FORCEPROP 0 LASTPIN (-3625 5300) $PN R5
J 0
(-3615 5310);
DISPLAY 0.489362 (-3615 5310);
PAINT MONO (-3615 5310);
FORCEPROP 0 LASTPIN (-3625 5250) $PN T7
J 0
(-3615 5260);
DISPLAY 0.489362 (-3615 5260);
PAINT MONO (-3615 5260);
FORCEPROP 0 LASTPIN (-3625 5200) $PN T6
J 0
(-3615 5210);
DISPLAY 0.489362 (-3615 5210);
PAINT MONO (-3615 5210);
FORCEPROP 0 LASTPIN (-3625 5150) $PN U7
J 0
(-3615 5160);
DISPLAY 0.489362 (-3615 5160);
PAINT MONO (-3615 5160);
FORCEPROP 0 LASTPIN (-3625 5050) $PN U5
J 0
(-3615 5060);
DISPLAY 0.489362 (-3615 5060);
PAINT MONO (-3615 5060);
FORCEPROP 0 LASTPIN (-3625 5000) $PN V7
J 0
(-3615 5010);
DISPLAY 0.489362 (-3615 5010);
PAINT MONO (-3615 5010);
FORCEPROP 0 LASTPIN (-3625 4950) $PN V6
J 0
(-3615 4960);
DISPLAY 0.489362 (-3615 4960);
PAINT MONO (-3615 4960);
FORCEPROP 0 LASTPIN (-3625 4900) $PN W7
J 0
(-3615 4910);
DISPLAY 0.489362 (-3615 4910);
PAINT MONO (-3615 4910);
FORCEPROP 0 LASTPIN (-3625 4850) $PN AA5
J 0
(-3615 4860);
DISPLAY 0.489362 (-3615 4860);
PAINT MONO (-3615 4860);
FORCEPROP 0 LASTPIN (-3625 4800) $PN AB7
J 0
(-3615 4810);
DISPLAY 0.489362 (-3615 4810);
PAINT MONO (-3615 4810);
FORCEPROP 0 LASTPIN (-3625 4750) $PN AB6
J 0
(-3615 4760);
DISPLAY 0.489362 (-3615 4760);
PAINT MONO (-3615 4760);
FORCEPROP 0 LASTPIN (-3625 4700) $PN AC7
J 0
(-3615 4710);
DISPLAY 0.489362 (-3615 4710);
PAINT MONO (-3615 4710);
FORCEPROP 0 LASTPIN (-3625 4600) $PN AC5
J 0
(-3615 4610);
DISPLAY 0.489362 (-3615 4610);
PAINT MONO (-3615 4610);
FORCEPROP 0 LASTPIN (-3625 4550) $PN AD7
J 0
(-3615 4560);
DISPLAY 0.489362 (-3615 4560);
PAINT MONO (-3615 4560);
FORCEPROP 0 LASTPIN (-3625 4500) $PN AD6
J 0
(-3615 4510);
DISPLAY 0.489362 (-3615 4510);
PAINT MONO (-3615 4510);
FORCEPROP 0 LASTPIN (-3625 4450) $PN AE7
J 0
(-3615 4460);
DISPLAY 0.489362 (-3615 4460);
PAINT MONO (-3615 4460);
FORCEPROP 0 LASTPIN (-3625 4400) $PN AG5
J 0
(-3615 4410);
DISPLAY 0.489362 (-3615 4410);
PAINT MONO (-3615 4410);
FORCEPROP 0 LASTPIN (-3625 4350) $PN AH7
J 0
(-3615 4360);
DISPLAY 0.489362 (-3615 4360);
PAINT MONO (-3615 4360);
FORCEPROP 0 LASTPIN (-3625 4300) $PN AH6
J 0
(-3615 4310);
DISPLAY 0.489362 (-3615 4310);
PAINT MONO (-3615 4310);
FORCEPROP 0 LASTPIN (-3625 4250) $PN AJ7
J 0
(-3615 4260);
DISPLAY 0.489362 (-3615 4260);
PAINT MONO (-3615 4260);
FORCEPROP 0 LASTPIN (-5225 5950) $PN G5
J 2
(-5235 5960);
DISPLAY 0.489362 (-5235 5960);
PAINT MONO (-5235 5960);
FORCEPROP 0 LASTPIN (-5225 5850) $PN N5
J 2
(-5235 5860);
DISPLAY 0.489362 (-5235 5860);
PAINT MONO (-5235 5860);
FORCEPROP 0 LASTPIN (-5225 5750) $PN W5
J 2
(-5235 5760);
DISPLAY 0.489362 (-5235 5760);
PAINT MONO (-5235 5760);
FORCEPROP 0 LASTPIN (-5225 5650) $PN AE5
J 2
(-5235 5660);
DISPLAY 0.489362 (-5235 5660);
PAINT MONO (-5235 5660);
FORCEPROP 0 LASTPIN (-5225 5550) $PN AL5
J 2
(-5235 5560);
DISPLAY 0.489362 (-5235 5560);
PAINT MONO (-5235 5560);
FORCEPROP 0 LASTPIN (-5225 5450) $PN J7
J 2
(-5235 5460);
DISPLAY 0.489362 (-5235 5460);
PAINT MONO (-5235 5460);
FORCEPROP 0 LASTPIN (-5225 5350) $PN R7
J 2
(-5235 5360);
DISPLAY 0.489362 (-5235 5360);
PAINT MONO (-5235 5360);
FORCEPROP 0 LASTPIN (-5225 5250) $PN AA7
J 2
(-5235 5260);
DISPLAY 0.489362 (-5235 5260);
PAINT MONO (-5235 5260);
FORCEPROP 0 LASTPIN (-5225 5150) $PN AG7
J 2
(-5235 5160);
DISPLAY 0.489362 (-5235 5160);
PAINT MONO (-5235 5160);
FORCEPROP 0 LASTPIN (-5225 5050) $PN AN7
J 2
(-5235 5060);
DISPLAY 0.489362 (-5235 5060);
PAINT MONO (-5235 5060);
FORCEPROP 0 LASTPIN (-5225 5900) $PN H6
J 2
(-5235 5910);
DISPLAY 0.489362 (-5235 5910);
PAINT MONO (-5235 5910);
FORCEPROP 0 LASTPIN (-5225 5800) $PN P6
J 2
(-5235 5810);
DISPLAY 0.489362 (-5235 5810);
PAINT MONO (-5235 5810);
FORCEPROP 0 LASTPIN (-5225 5700) $PN Y6
J 2
(-5235 5710);
DISPLAY 0.489362 (-5235 5710);
PAINT MONO (-5235 5710);
FORCEPROP 0 LASTPIN (-5225 5600) $PN AF6
J 2
(-5235 5610);
DISPLAY 0.489362 (-5235 5610);
PAINT MONO (-5235 5610);
FORCEPROP 0 LASTPIN (-5225 5500) $PN AM6
J 2
(-5235 5510);
DISPLAY 0.489362 (-5235 5510);
PAINT MONO (-5235 5510);
FORCEPROP 0 LASTPIN (-5225 5400) $PN H7
J 2
(-5235 5410);
DISPLAY 0.489362 (-5235 5410);
PAINT MONO (-5235 5410);
FORCEPROP 0 LASTPIN (-5225 5300) $PN P7
J 2
(-5235 5310);
DISPLAY 0.489362 (-5235 5310);
PAINT MONO (-5235 5310);
FORCEPROP 0 LASTPIN (-5225 5200) $PN Y7
J 2
(-5235 5210);
DISPLAY 0.489362 (-5235 5210);
PAINT MONO (-5235 5210);
FORCEPROP 0 LASTPIN (-5225 5100) $PN AF7
J 2
(-5235 5110);
DISPLAY 0.489362 (-5235 5110);
PAINT MONO (-5235 5110);
FORCEPROP 0 LASTPIN (-5225 5000) $PN AM7
J 2
(-5235 5010);
DISPLAY 0.489362 (-5235 5010);
PAINT MONO (-5235 5010);
FORCEPROP 0 LASTPIN (-5225 2550) $PN BC7
J 2
(-5235 2560);
DISPLAY 0.489362 (-5235 2560);
PAINT MONO (-5235 2560);
FORCEPROP 0 LASTPIN (-5225 2450) $PN BM7
J 2
(-5235 2460);
DISPLAY 0.489362 (-5235 2460);
PAINT MONO (-5235 2460);
FORCEPROP 0 LASTPIN (-5225 2400) $PN BN5
J 2
(-5235 2410);
DISPLAY 0.489362 (-5235 2410);
PAINT MONO (-5235 2410);
FORCEPROP 0 LASTPIN (-5225 2300) $PN BP6
J 2
(-5235 2310);
DISPLAY 0.489362 (-5235 2310);
PAINT MONO (-5235 2310);
FORCEPROP 0 LASTPIN (-5225 1400) $PN BL5
J 2
(-5235 1410);
DISPLAY 0.489362 (-5235 1410);
PAINT MONO (-5235 1410);
FORCEPROP 0 LASTPIN (-5225 1350) $PN BM6
J 2
(-5235 1360);
DISPLAY 0.489362 (-5235 1360);
PAINT MONO (-5235 1360);
FORCEPROP 0 LASTPIN (-5225 1250) $PN BR5
J 2
(-5235 1260);
DISPLAY 0.489362 (-5235 1260);
PAINT MONO (-5235 1260);
FORCEPROP 0 LASTPIN (-5225 3400) $PN BG7
J 2
(-5235 3410);
DISPLAY 0.489362 (-5235 3410);
PAINT MONO (-5235 3410);
FORCEPROP 0 LASTPIN (-5225 3350) $PN BH7
J 2
(-5235 3360);
DISPLAY 0.489362 (-5235 3360);
PAINT MONO (-5235 3360);
FORCEPROP 0 LASTPIN (-5225 3300) $PN BH6
J 2
(-5235 3310);
DISPLAY 0.489362 (-5235 3310);
PAINT MONO (-5235 3310);
FORCEPROP 0 LASTPIN (-5225 3250) $PN BJ5
J 2
(-5235 3260);
DISPLAY 0.489362 (-5235 3260);
PAINT MONO (-5235 3260);
FORCEPROP 0 LASTPIN (-5225 3200) $PN BJ7
J 2
(-5235 3210);
DISPLAY 0.489362 (-5235 3210);
PAINT MONO (-5235 3210);
FORCEPROP 0 LASTPIN (-5225 3150) $PN BK7
J 2
(-5235 3160);
DISPLAY 0.489362 (-5235 3160);
PAINT MONO (-5235 3160);
FORCEPROP 0 LASTPIN (-5225 3100) $PN BK6
J 2
(-5235 3110);
DISPLAY 0.489362 (-5235 3110);
PAINT MONO (-5235 3110);
FORCEPROP 0 LASTPIN (-3625 1900) $PN BY6
J 0
(-3615 1910);
DISPLAY 0.489362 (-3615 1910);
PAINT MONO (-3615 1910);
FORCEPROP 0 LASTPIN (-3625 1850) $PN CA7
J 0
(-3615 1860);
DISPLAY 0.489362 (-3615 1860);
PAINT MONO (-3615 1860);
FORCEPROP 0 LASTPIN (-3625 1800) $PN CA5
J 0
(-3615 1810);
DISPLAY 0.489362 (-3615 1810);
PAINT MONO (-3615 1810);
FORCEPROP 0 LASTPIN (-3625 1750) $PN CB7
J 0
(-3615 1760);
DISPLAY 0.489362 (-3615 1760);
PAINT MONO (-3615 1760);
FORCEPROP 0 LASTPIN (-3625 1700) $PN BT6
J 0
(-3615 1710);
DISPLAY 0.489362 (-3615 1710);
PAINT MONO (-3615 1710);
FORCEPROP 0 LASTPIN (-3625 1650) $PN BU7
J 0
(-3615 1660);
DISPLAY 0.489362 (-3615 1660);
PAINT MONO (-3615 1660);
FORCEPROP 0 LASTPIN (-3625 1600) $PN BU5
J 0
(-3615 1610);
DISPLAY 0.489362 (-3615 1610);
PAINT MONO (-3615 1610);
FORCEPROP 0 LASTPIN (-3625 1550) $PN BV7
J 0
(-3615 1560);
DISPLAY 0.489362 (-3615 1560);
PAINT MONO (-3615 1560);
FORCEPROP 0 LASTPIN (-3625 4150) $PN CB6
J 0
(-3615 4160);
DISPLAY 0.489362 (-3615 4160);
PAINT MONO (-3615 4160);
FORCEPROP 0 LASTPIN (-3625 4100) $PN CC7
J 0
(-3615 4110);
DISPLAY 0.489362 (-3615 4110);
PAINT MONO (-3615 4110);
FORCEPROP 0 LASTPIN (-3625 4050) $PN CC5
J 0
(-3615 4060);
DISPLAY 0.489362 (-3615 4060);
PAINT MONO (-3615 4060);
FORCEPROP 0 LASTPIN (-3625 4000) $PN CD7
J 0
(-3615 4010);
DISPLAY 0.489362 (-3615 4010);
PAINT MONO (-3615 4010);
FORCEPROP 0 LASTPIN (-3625 3950) $PN CF6
J 0
(-3615 3960);
DISPLAY 0.489362 (-3615 3960);
PAINT MONO (-3615 3960);
FORCEPROP 0 LASTPIN (-3625 3900) $PN CG7
J 0
(-3615 3910);
DISPLAY 0.489362 (-3615 3910);
PAINT MONO (-3615 3910);
FORCEPROP 0 LASTPIN (-3625 3850) $PN CG5
J 0
(-3615 3860);
DISPLAY 0.489362 (-3615 3860);
PAINT MONO (-3615 3860);
FORCEPROP 0 LASTPIN (-3625 3800) $PN CH7
J 0
(-3615 3810);
DISPLAY 0.489362 (-3615 3810);
PAINT MONO (-3615 3810);
FORCEPROP 0 LASTPIN (-3625 3700) $PN CH6
J 0
(-3615 3710);
DISPLAY 0.489362 (-3615 3710);
PAINT MONO (-3615 3710);
FORCEPROP 0 LASTPIN (-3625 3650) $PN CJ7
J 0
(-3615 3660);
DISPLAY 0.489362 (-3615 3660);
PAINT MONO (-3615 3660);
FORCEPROP 0 LASTPIN (-3625 3600) $PN CJ5
J 0
(-3615 3610);
DISPLAY 0.489362 (-3615 3610);
PAINT MONO (-3615 3610);
FORCEPROP 0 LASTPIN (-3625 3550) $PN CK7
J 0
(-3615 3560);
DISPLAY 0.489362 (-3615 3560);
PAINT MONO (-3615 3560);
FORCEPROP 0 LASTPIN (-3625 3500) $PN CM6
J 0
(-3615 3510);
DISPLAY 0.489362 (-3615 3510);
PAINT MONO (-3615 3510);
FORCEPROP 0 LASTPIN (-3625 3450) $PN CN7
J 0
(-3615 3460);
DISPLAY 0.489362 (-3615 3460);
PAINT MONO (-3615 3460);
FORCEPROP 0 LASTPIN (-3625 3400) $PN CN5
J 0
(-3615 3410);
DISPLAY 0.489362 (-3615 3410);
PAINT MONO (-3615 3410);
FORCEPROP 0 LASTPIN (-3625 3350) $PN CP7
J 0
(-3615 3360);
DISPLAY 0.489362 (-3615 3360);
PAINT MONO (-3615 3360);
FORCEPROP 0 LASTPIN (-3625 3250) $PN CP6
J 0
(-3615 3260);
DISPLAY 0.489362 (-3615 3260);
PAINT MONO (-3615 3260);
FORCEPROP 0 LASTPIN (-3625 3200) $PN CR7
J 0
(-3615 3210);
DISPLAY 0.489362 (-3615 3210);
PAINT MONO (-3615 3210);
FORCEPROP 0 LASTPIN (-3625 3150) $PN CR5
J 0
(-3615 3160);
DISPLAY 0.489362 (-3615 3160);
PAINT MONO (-3615 3160);
FORCEPROP 0 LASTPIN (-3625 3100) $PN CT7
J 0
(-3615 3110);
DISPLAY 0.489362 (-3615 3110);
PAINT MONO (-3615 3110);
FORCEPROP 0 LASTPIN (-3625 3050) $PN CV6
J 0
(-3615 3060);
DISPLAY 0.489362 (-3615 3060);
PAINT MONO (-3615 3060);
FORCEPROP 0 LASTPIN (-3625 3000) $PN CW7
J 0
(-3615 3010);
DISPLAY 0.489362 (-3615 3010);
PAINT MONO (-3615 3010);
FORCEPROP 0 LASTPIN (-3625 2950) $PN CW5
J 0
(-3615 2960);
DISPLAY 0.489362 (-3615 2960);
PAINT MONO (-3615 2960);
FORCEPROP 0 LASTPIN (-3625 2900) $PN CY7
J 0
(-3615 2910);
DISPLAY 0.489362 (-3615 2910);
PAINT MONO (-3615 2910);
FORCEPROP 0 LASTPIN (-3625 2800) $PN CY6
J 0
(-3615 2810);
DISPLAY 0.489362 (-3615 2810);
PAINT MONO (-3615 2810);
FORCEPROP 0 LASTPIN (-3625 2750) $PN DA7
J 0
(-3615 2760);
DISPLAY 0.489362 (-3615 2760);
PAINT MONO (-3615 2760);
FORCEPROP 0 LASTPIN (-3625 2700) $PN DA5
J 0
(-3615 2710);
DISPLAY 0.489362 (-3615 2710);
PAINT MONO (-3615 2710);
FORCEPROP 0 LASTPIN (-3625 2650) $PN DB7
J 0
(-3615 2660);
DISPLAY 0.489362 (-3615 2660);
PAINT MONO (-3615 2660);
FORCEPROP 0 LASTPIN (-3625 2600) $PN DD6
J 0
(-3615 2610);
DISPLAY 0.489362 (-3615 2610);
PAINT MONO (-3615 2610);
FORCEPROP 0 LASTPIN (-3625 2550) $PN DE7
J 0
(-3615 2560);
DISPLAY 0.489362 (-3615 2560);
PAINT MONO (-3615 2560);
FORCEPROP 0 LASTPIN (-3625 2500) $PN DE5
J 0
(-3615 2510);
DISPLAY 0.489362 (-3615 2510);
PAINT MONO (-3615 2510);
FORCEPROP 0 LASTPIN (-3625 2450) $PN DF7
J 0
(-3615 2460);
DISPLAY 0.489362 (-3615 2460);
PAINT MONO (-3615 2460);
FORCEPROP 0 LASTPIN (-5225 4900) $PN CD6
J 2
(-5235 4910);
DISPLAY 0.489362 (-5235 4910);
PAINT MONO (-5235 4910);
FORCEPROP 0 LASTPIN (-5225 4800) $PN CK6
J 2
(-5235 4810);
DISPLAY 0.489362 (-5235 4810);
PAINT MONO (-5235 4810);
FORCEPROP 0 LASTPIN (-5225 4700) $PN CT6
J 2
(-5235 4710);
DISPLAY 0.489362 (-5235 4710);
PAINT MONO (-5235 4710);
FORCEPROP 0 LASTPIN (-5225 4600) $PN DB6
J 2
(-5235 4610);
DISPLAY 0.489362 (-5235 4610);
PAINT MONO (-5235 4610);
FORCEPROP 0 LASTPIN (-5225 4500) $PN BY7
J 2
(-5235 4510);
DISPLAY 0.489362 (-5235 4510);
PAINT MONO (-5235 4510);
FORCEPROP 0 LASTPIN (-5225 4400) $PN CF7
J 2
(-5235 4410);
DISPLAY 0.489362 (-5235 4410);
PAINT MONO (-5235 4410);
FORCEPROP 0 LASTPIN (-5225 4300) $PN CM7
J 2
(-5235 4310);
DISPLAY 0.489362 (-5235 4310);
PAINT MONO (-5235 4310);
FORCEPROP 0 LASTPIN (-5225 4200) $PN CV7
J 2
(-5235 4210);
DISPLAY 0.489362 (-5235 4210);
PAINT MONO (-5235 4210);
FORCEPROP 0 LASTPIN (-5225 4100) $PN DD7
J 2
(-5235 4110);
DISPLAY 0.489362 (-5235 4110);
PAINT MONO (-5235 4110);
FORCEPROP 0 LASTPIN (-5225 4000) $PN BV6
J 2
(-5235 4010);
DISPLAY 0.489362 (-5235 4010);
PAINT MONO (-5235 4010);
FORCEPROP 0 LASTPIN (-5225 4850) $PN CE5
J 2
(-5235 4860);
DISPLAY 0.489362 (-5235 4860);
PAINT MONO (-5235 4860);
FORCEPROP 0 LASTPIN (-5225 4750) $PN CL5
J 2
(-5235 4760);
DISPLAY 0.489362 (-5235 4760);
PAINT MONO (-5235 4760);
FORCEPROP 0 LASTPIN (-5225 4650) $PN CU5
J 2
(-5235 4660);
DISPLAY 0.489362 (-5235 4660);
PAINT MONO (-5235 4660);
FORCEPROP 0 LASTPIN (-5225 4550) $PN DC5
J 2
(-5235 4560);
DISPLAY 0.489362 (-5235 4560);
PAINT MONO (-5235 4560);
FORCEPROP 0 LASTPIN (-5225 4450) $PN BW7
J 2
(-5235 4460);
DISPLAY 0.489362 (-5235 4460);
PAINT MONO (-5235 4460);
FORCEPROP 0 LASTPIN (-5225 4350) $PN CE7
J 2
(-5235 4360);
DISPLAY 0.489362 (-5235 4360);
PAINT MONO (-5235 4360);
FORCEPROP 0 LASTPIN (-5225 4250) $PN CL7
J 2
(-5235 4260);
DISPLAY 0.489362 (-5235 4260);
PAINT MONO (-5235 4260);
FORCEPROP 0 LASTPIN (-5225 4150) $PN CU7
J 2
(-5235 4160);
DISPLAY 0.489362 (-5235 4160);
PAINT MONO (-5235 4160);
FORCEPROP 0 LASTPIN (-5225 4050) $PN DC7
J 2
(-5235 4060);
DISPLAY 0.489362 (-5235 4060);
PAINT MONO (-5235 4060);
FORCEPROP 0 LASTPIN (-5225 3950) $PN BW5
J 2
(-5235 3960);
DISPLAY 0.489362 (-5235 3960);
PAINT MONO (-5235 3960);
FORCEPROP 0 LASTPIN (-5225 2200) $PN BL7
J 2
(-5235 2210);
DISPLAY 0.489362 (-5235 2210);
PAINT MONO (-5235 2210);
FORCEPROP 0 LASTPIN (-5225 1150) $PN BF7
J 2
(-5235 1160);
DISPLAY 0.489362 (-5235 1160);
PAINT MONO (-5235 1160);
FORCEPROP 2 LAST PART_TYPE SMLF
J 0
(-5050 6500);
DISPLAY 1.021277 (-5050 6500);
FORCEPROP 1 LAST MATERIAL IO
J 0
(-5070 6132);
DISPLAY 0.489362 (-5070 6132);
PAINT SKYBLUE (-5070 6132);
FORCEPROP 2 LAST VALUE SOCKET6096_13568-001
J 0
(-5050 6450);
DISPLAY 0.489362 (-5050 6450);
PAINT SKYBLUE (-5050 6450);
FORCEPROP 1 LAST PART_NUMBER DGA^6000030
J 0
(-5070 6259);
DISPLAY 0.489362 (-5070 6259);
PAINT SKYBLUE (-5070 6259);
FORCEPROP 1 LAST NEEDS_NO_SIZE TRUE
J 0
(-4425 3575);
DISPLAY 0.723404 (-4425 3575);
PAINT GREEN (-4425 3575);
DISPLAY INVISIBLE (-4425 3575);
FORCEPROP 1 LAST CDS_LMAN_SYM_OUTLINE -650,2525,650,-2525
J 0
(-4425 3575);
DISPLAY 0.468085 (-4425 3575);
PAINT GREEN (-4425 3575);
DISPLAY INVISIBLE (-4425 3575);
FORCEPROP 2 LAST CDS_LIB pure_quanta
J 0
(-4425 3575);
DISPLAY INVISIBLE (-4425 3575);
FORCEPROP 1 LAST PATH I159
J 0
(-4425 3575);
DISPLAY 0.723404 (-4425 3575);
PAINT GREEN (-4425 3575);
DISPLAY INVISIBLE (-4425 3575);
FORCEADD OFFPAGE..3
(-2425 5975);
FORCEPROP 2 LAST $XR0 95 
J 0
(-2211 5975);
DISPLAY 0.638298 (-2211 5975);
PAINT MONO (-2211 5975);
FORCEPROP 2 LAST PATH I160
J 0
(-2200 6025);
DISPLAY 1.021277 (-2200 6025);
DISPLAY INVISIBLE (-2200 6025);
FORCEPROP 1 LAST COMMENT_BODY TRUE
J 0
(-2475 5875);
DISPLAY 0.872340 (-2475 5875);
PAINT GREEN (-2475 5875);
DISPLAY INVISIBLE (-2475 5875);
FORCEPROP 1 LAST OFFPAGE TRUE
J 0
(-2100 5850);
DISPLAY 0.872340 (-2100 5850);
PAINT GREEN (-2100 5850);
DISPLAY INVISIBLE (-2100 5850);
FORCEPROP 2 LAST CDS_LIB mstr_standard
J 0
(-2425 5975);
DISPLAY 0.723404 (-2425 5975);
PAINT MONO (-2425 5975);
DISPLAY INVISIBLE (-2425 5975);
FORCEADD OFFPAGE..3
(-2425 4175);
FORCEPROP 2 LAST $XR0 95 
J 0
(-2211 4175);
DISPLAY 0.638298 (-2211 4175);
PAINT MONO (-2211 4175);
FORCEPROP 2 LAST PATH I161
J 0
(-2200 4225);
DISPLAY 1.021277 (-2200 4225);
DISPLAY INVISIBLE (-2200 4225);
FORCEPROP 1 LAST COMMENT_BODY TRUE
J 0
(-2475 4075);
DISPLAY 0.872340 (-2475 4075);
PAINT GREEN (-2475 4075);
DISPLAY INVISIBLE (-2475 4075);
FORCEPROP 1 LAST OFFPAGE TRUE
J 0
(-2100 4050);
DISPLAY 0.872340 (-2100 4050);
PAINT GREEN (-2100 4050);
DISPLAY INVISIBLE (-2100 4050);
FORCEPROP 2 LAST CDS_LIB mstr_standard
J 0
(-2425 4175);
DISPLAY 0.723404 (-2425 4175);
PAINT MONO (-2425 4175);
DISPLAY INVISIBLE (-2425 4175);
FORCEADD TAP..1
(-3150 5950);
FORCEPROP 3 LASTPIN (-3200 5950) SIG_NAME M_K_CPU0_SA_DQ<0>
J 0
(-3190 5960);
DISPLAY 0.659574 (-3190 5960);
PAINT MONO (-3190 5960);
DISPLAY INVISIBLE (-3190 5960);
FORCEPROP 1 LASTPIN (-3200 5950) BN 0
J 0
(-3212 5958);
DISPLAY 0.489362 (-3212 5958);
PAINT GREEN (-3212 5958);
FORCEPROP 2 LAST CDS_LIB mstr_standard
J 0
(-3150 5950);
DISPLAY 0.723404 (-3150 5950);
PAINT MONO (-3150 5950);
DISPLAY INVISIBLE (-3150 5950);
FORCEPROP 1 LAST BODY_TYPE PLUMBING
J 0
(-3150 6000);
DISPLAY 0.872340 (-3150 6000);
PAINT GREEN (-3150 6000);
DISPLAY INVISIBLE (-3150 6000);
FORCEPROP 1 LAST HDL_TAP TRUE
J 0
(-2825 5825);
DISPLAY 0.872340 (-2825 5825);
DISPLAY INVISIBLE (-2825 5825);
FORCEPROP 1 LAST PATH I162
J 0
(-3152 5950);
DISPLAY 0.872340 (-3152 5950);
PAINT GREEN (-3152 5950);
DISPLAY INVISIBLE (-3152 5950);
FORCEADD TAP..1
(-3150 5900);
FORCEPROP 3 LASTPIN (-3200 5900) SIG_NAME M_K_CPU0_SA_DQ<1>
J 0
(-3190 5910);
DISPLAY 0.659574 (-3190 5910);
PAINT MONO (-3190 5910);
DISPLAY INVISIBLE (-3190 5910);
FORCEPROP 1 LASTPIN (-3200 5900) BN 1
J 0
(-3212 5908);
DISPLAY 0.489362 (-3212 5908);
PAINT GREEN (-3212 5908);
FORCEPROP 2 LAST CDS_LIB mstr_standard
J 0
(-3150 5900);
DISPLAY 0.723404 (-3150 5900);
PAINT MONO (-3150 5900);
DISPLAY INVISIBLE (-3150 5900);
FORCEPROP 1 LAST BODY_TYPE PLUMBING
J 0
(-3150 5950);
DISPLAY 0.872340 (-3150 5950);
PAINT GREEN (-3150 5950);
DISPLAY INVISIBLE (-3150 5950);
FORCEPROP 1 LAST HDL_TAP TRUE
J 0
(-2825 5775);
DISPLAY 0.872340 (-2825 5775);
DISPLAY INVISIBLE (-2825 5775);
FORCEPROP 1 LAST PATH I163
J 0
(-3152 5900);
DISPLAY 0.872340 (-3152 5900);
PAINT GREEN (-3152 5900);
DISPLAY INVISIBLE (-3152 5900);
FORCEADD TAP..1
(-3150 5850);
FORCEPROP 3 LASTPIN (-3200 5850) SIG_NAME M_K_CPU0_SA_DQ<2>
J 0
(-3190 5860);
DISPLAY 0.659574 (-3190 5860);
PAINT MONO (-3190 5860);
DISPLAY INVISIBLE (-3190 5860);
FORCEPROP 1 LASTPIN (-3200 5850) BN 2
J 0
(-3212 5858);
DISPLAY 0.489362 (-3212 5858);
PAINT GREEN (-3212 5858);
FORCEPROP 2 LAST CDS_LIB mstr_standard
J 0
(-3150 5850);
DISPLAY 0.723404 (-3150 5850);
PAINT MONO (-3150 5850);
DISPLAY INVISIBLE (-3150 5850);
FORCEPROP 1 LAST BODY_TYPE PLUMBING
J 0
(-3150 5900);
DISPLAY 0.872340 (-3150 5900);
PAINT GREEN (-3150 5900);
DISPLAY INVISIBLE (-3150 5900);
FORCEPROP 1 LAST HDL_TAP TRUE
J 0
(-2825 5725);
DISPLAY 0.872340 (-2825 5725);
DISPLAY INVISIBLE (-2825 5725);
FORCEPROP 1 LAST PATH I164
J 0
(-3152 5850);
DISPLAY 0.872340 (-3152 5850);
PAINT GREEN (-3152 5850);
DISPLAY INVISIBLE (-3152 5850);
FORCEADD TAP..1
(-3150 5800);
FORCEPROP 3 LASTPIN (-3200 5800) SIG_NAME M_K_CPU0_SA_DQ<3>
J 0
(-3190 5810);
DISPLAY 0.659574 (-3190 5810);
PAINT MONO (-3190 5810);
DISPLAY INVISIBLE (-3190 5810);
FORCEPROP 1 LASTPIN (-3200 5800) BN 3
J 0
(-3212 5808);
DISPLAY 0.489362 (-3212 5808);
PAINT GREEN (-3212 5808);
FORCEPROP 2 LAST CDS_LIB mstr_standard
J 0
(-3150 5800);
DISPLAY 0.723404 (-3150 5800);
PAINT MONO (-3150 5800);
DISPLAY INVISIBLE (-3150 5800);
FORCEPROP 1 LAST BODY_TYPE PLUMBING
J 0
(-3150 5850);
DISPLAY 0.872340 (-3150 5850);
PAINT GREEN (-3150 5850);
DISPLAY INVISIBLE (-3150 5850);
FORCEPROP 1 LAST HDL_TAP TRUE
J 0
(-2825 5675);
DISPLAY 0.872340 (-2825 5675);
DISPLAY INVISIBLE (-2825 5675);
FORCEPROP 1 LAST PATH I165
J 0
(-3152 5800);
DISPLAY 0.872340 (-3152 5800);
PAINT GREEN (-3152 5800);
DISPLAY INVISIBLE (-3152 5800);
FORCEADD TAP..1
(-3150 5700);
FORCEPROP 3 LASTPIN (-3200 5700) SIG_NAME M_K_CPU0_SA_DQ<5>
J 0
(-3190 5710);
DISPLAY 0.659574 (-3190 5710);
PAINT MONO (-3190 5710);
DISPLAY INVISIBLE (-3190 5710);
FORCEPROP 1 LASTPIN (-3200 5700) BN 5
J 0
(-3212 5708);
DISPLAY 0.489362 (-3212 5708);
PAINT GREEN (-3212 5708);
FORCEPROP 2 LAST CDS_LIB mstr_standard
J 0
(-3150 5700);
DISPLAY 0.723404 (-3150 5700);
PAINT MONO (-3150 5700);
DISPLAY INVISIBLE (-3150 5700);
FORCEPROP 1 LAST BODY_TYPE PLUMBING
J 0
(-3150 5750);
DISPLAY 0.872340 (-3150 5750);
PAINT GREEN (-3150 5750);
DISPLAY INVISIBLE (-3150 5750);
FORCEPROP 1 LAST HDL_TAP TRUE
J 0
(-2825 5575);
DISPLAY 0.872340 (-2825 5575);
DISPLAY INVISIBLE (-2825 5575);
FORCEPROP 1 LAST PATH I166
J 0
(-3152 5700);
DISPLAY 0.872340 (-3152 5700);
PAINT GREEN (-3152 5700);
DISPLAY INVISIBLE (-3152 5700);
FORCEADD TAP..1
(-3150 5650);
FORCEPROP 3 LASTPIN (-3200 5650) SIG_NAME M_K_CPU0_SA_DQ<6>
J 0
(-3190 5660);
DISPLAY 0.659574 (-3190 5660);
PAINT MONO (-3190 5660);
DISPLAY INVISIBLE (-3190 5660);
FORCEPROP 1 LASTPIN (-3200 5650) BN 6
J 0
(-3212 5658);
DISPLAY 0.489362 (-3212 5658);
PAINT GREEN (-3212 5658);
FORCEPROP 2 LAST CDS_LIB mstr_standard
J 0
(-3150 5650);
DISPLAY 0.723404 (-3150 5650);
PAINT MONO (-3150 5650);
DISPLAY INVISIBLE (-3150 5650);
FORCEPROP 1 LAST BODY_TYPE PLUMBING
J 0
(-3150 5700);
DISPLAY 0.872340 (-3150 5700);
PAINT GREEN (-3150 5700);
DISPLAY INVISIBLE (-3150 5700);
FORCEPROP 1 LAST HDL_TAP TRUE
J 0
(-2825 5525);
DISPLAY 0.872340 (-2825 5525);
DISPLAY INVISIBLE (-2825 5525);
FORCEPROP 1 LAST PATH I167
J 0
(-3152 5650);
DISPLAY 0.872340 (-3152 5650);
PAINT GREEN (-3152 5650);
DISPLAY INVISIBLE (-3152 5650);
FORCEADD TAP..1
(-3150 5750);
FORCEPROP 3 LASTPIN (-3200 5750) SIG_NAME M_K_CPU0_SA_DQ<4>
J 0
(-3190 5760);
DISPLAY 0.659574 (-3190 5760);
PAINT MONO (-3190 5760);
DISPLAY INVISIBLE (-3190 5760);
FORCEPROP 1 LASTPIN (-3200 5750) BN 4
J 0
(-3212 5758);
DISPLAY 0.489362 (-3212 5758);
PAINT GREEN (-3212 5758);
FORCEPROP 2 LAST CDS_LIB mstr_standard
J 0
(-3150 5750);
DISPLAY 0.723404 (-3150 5750);
PAINT MONO (-3150 5750);
DISPLAY INVISIBLE (-3150 5750);
FORCEPROP 1 LAST BODY_TYPE PLUMBING
J 0
(-3150 5800);
DISPLAY 0.872340 (-3150 5800);
PAINT GREEN (-3150 5800);
DISPLAY INVISIBLE (-3150 5800);
FORCEPROP 1 LAST HDL_TAP TRUE
J 0
(-2825 5625);
DISPLAY 0.872340 (-2825 5625);
DISPLAY INVISIBLE (-2825 5625);
FORCEPROP 1 LAST PATH I168
J 0
(-3152 5750);
DISPLAY 0.872340 (-3152 5750);
PAINT GREEN (-3152 5750);
DISPLAY INVISIBLE (-3152 5750);
FORCEADD TAP..1
(-3150 5600);
FORCEPROP 3 LASTPIN (-3200 5600) SIG_NAME M_K_CPU0_SA_DQ<7>
J 0
(-3190 5610);
DISPLAY 0.659574 (-3190 5610);
PAINT MONO (-3190 5610);
DISPLAY INVISIBLE (-3190 5610);
FORCEPROP 1 LASTPIN (-3200 5600) BN 7
J 0
(-3212 5608);
DISPLAY 0.489362 (-3212 5608);
PAINT GREEN (-3212 5608);
FORCEPROP 2 LAST CDS_LIB mstr_standard
J 0
(-3150 5600);
DISPLAY 0.723404 (-3150 5600);
PAINT MONO (-3150 5600);
DISPLAY INVISIBLE (-3150 5600);
FORCEPROP 1 LAST BODY_TYPE PLUMBING
J 0
(-3150 5650);
DISPLAY 0.872340 (-3150 5650);
PAINT GREEN (-3150 5650);
DISPLAY INVISIBLE (-3150 5650);
FORCEPROP 1 LAST HDL_TAP TRUE
J 0
(-2825 5475);
DISPLAY 0.872340 (-2825 5475);
DISPLAY INVISIBLE (-2825 5475);
FORCEPROP 1 LAST PATH I169
J 0
(-3152 5600);
DISPLAY 0.872340 (-3152 5600);
PAINT GREEN (-3152 5600);
DISPLAY INVISIBLE (-3152 5600);
FORCEADD TAP..1
(-3150 5400);
FORCEPROP 3 LASTPIN (-3200 5400) SIG_NAME M_K_CPU0_SA_DQ<10>
J 0
(-3190 5410);
DISPLAY 0.659574 (-3190 5410);
PAINT MONO (-3190 5410);
DISPLAY INVISIBLE (-3190 5410);
FORCEPROP 1 LASTPIN (-3200 5400) BN 10
J 0
(-3212 5408);
DISPLAY 0.489362 (-3212 5408);
PAINT GREEN (-3212 5408);
FORCEPROP 2 LAST CDS_LIB mstr_standard
J 0
(-3150 5400);
DISPLAY 0.723404 (-3150 5400);
PAINT MONO (-3150 5400);
DISPLAY INVISIBLE (-3150 5400);
FORCEPROP 1 LAST BODY_TYPE PLUMBING
J 0
(-3150 5450);
DISPLAY 0.872340 (-3150 5450);
PAINT GREEN (-3150 5450);
DISPLAY INVISIBLE (-3150 5450);
FORCEPROP 1 LAST HDL_TAP TRUE
J 0
(-2825 5275);
DISPLAY 0.872340 (-2825 5275);
DISPLAY INVISIBLE (-2825 5275);
FORCEPROP 1 LAST PATH I170
J 0
(-3152 5400);
DISPLAY 0.872340 (-3152 5400);
PAINT GREEN (-3152 5400);
DISPLAY INVISIBLE (-3152 5400);
FORCEADD TAP..1
(-3150 5450);
FORCEPROP 3 LASTPIN (-3200 5450) SIG_NAME M_K_CPU0_SA_DQ<9>
J 0
(-3190 5460);
DISPLAY 0.659574 (-3190 5460);
PAINT MONO (-3190 5460);
DISPLAY INVISIBLE (-3190 5460);
FORCEPROP 1 LASTPIN (-3200 5450) BN 9
J 0
(-3212 5458);
DISPLAY 0.489362 (-3212 5458);
PAINT GREEN (-3212 5458);
FORCEPROP 2 LAST CDS_LIB mstr_standard
J 0
(-3150 5450);
DISPLAY 0.723404 (-3150 5450);
PAINT MONO (-3150 5450);
DISPLAY INVISIBLE (-3150 5450);
FORCEPROP 1 LAST BODY_TYPE PLUMBING
J 0
(-3150 5500);
DISPLAY 0.872340 (-3150 5500);
PAINT GREEN (-3150 5500);
DISPLAY INVISIBLE (-3150 5500);
FORCEPROP 1 LAST HDL_TAP TRUE
J 0
(-2825 5325);
DISPLAY 0.872340 (-2825 5325);
DISPLAY INVISIBLE (-2825 5325);
FORCEPROP 1 LAST PATH I171
J 0
(-3152 5450);
DISPLAY 0.872340 (-3152 5450);
PAINT GREEN (-3152 5450);
DISPLAY INVISIBLE (-3152 5450);
FORCEADD TAP..1
(-3150 5500);
FORCEPROP 3 LASTPIN (-3200 5500) SIG_NAME M_K_CPU0_SA_DQ<8>
J 0
(-3190 5510);
DISPLAY 0.659574 (-3190 5510);
PAINT MONO (-3190 5510);
DISPLAY INVISIBLE (-3190 5510);
FORCEPROP 1 LASTPIN (-3200 5500) BN 8
J 0
(-3212 5508);
DISPLAY 0.489362 (-3212 5508);
PAINT GREEN (-3212 5508);
FORCEPROP 2 LAST CDS_LIB mstr_standard
J 0
(-3150 5500);
DISPLAY 0.723404 (-3150 5500);
PAINT MONO (-3150 5500);
DISPLAY INVISIBLE (-3150 5500);
FORCEPROP 1 LAST BODY_TYPE PLUMBING
J 0
(-3150 5550);
DISPLAY 0.872340 (-3150 5550);
PAINT GREEN (-3150 5550);
DISPLAY INVISIBLE (-3150 5550);
FORCEPROP 1 LAST HDL_TAP TRUE
J 0
(-2825 5375);
DISPLAY 0.872340 (-2825 5375);
DISPLAY INVISIBLE (-2825 5375);
FORCEPROP 1 LAST PATH I172
J 0
(-3152 5500);
DISPLAY 0.872340 (-3152 5500);
PAINT GREEN (-3152 5500);
DISPLAY INVISIBLE (-3152 5500);
FORCEADD TAP..1
(-3150 5250);
FORCEPROP 3 LASTPIN (-3200 5250) SIG_NAME M_K_CPU0_SA_DQ<13>
J 0
(-3190 5260);
DISPLAY 0.659574 (-3190 5260);
PAINT MONO (-3190 5260);
DISPLAY INVISIBLE (-3190 5260);
FORCEPROP 1 LASTPIN (-3200 5250) BN 13
J 0
(-3212 5258);
DISPLAY 0.489362 (-3212 5258);
PAINT GREEN (-3212 5258);
FORCEPROP 2 LAST CDS_LIB mstr_standard
J 0
(-3150 5250);
DISPLAY 0.723404 (-3150 5250);
PAINT MONO (-3150 5250);
DISPLAY INVISIBLE (-3150 5250);
FORCEPROP 1 LAST BODY_TYPE PLUMBING
J 0
(-3150 5300);
DISPLAY 0.872340 (-3150 5300);
PAINT GREEN (-3150 5300);
DISPLAY INVISIBLE (-3150 5300);
FORCEPROP 1 LAST HDL_TAP TRUE
J 0
(-2825 5125);
DISPLAY 0.872340 (-2825 5125);
DISPLAY INVISIBLE (-2825 5125);
FORCEPROP 1 LAST PATH I173
J 0
(-3152 5250);
DISPLAY 0.872340 (-3152 5250);
PAINT GREEN (-3152 5250);
DISPLAY INVISIBLE (-3152 5250);
FORCEADD TAP..1
(-3150 5350);
FORCEPROP 3 LASTPIN (-3200 5350) SIG_NAME M_K_CPU0_SA_DQ<11>
J 0
(-3190 5360);
DISPLAY 0.659574 (-3190 5360);
PAINT MONO (-3190 5360);
DISPLAY INVISIBLE (-3190 5360);
FORCEPROP 1 LASTPIN (-3200 5350) BN 11
J 0
(-3212 5358);
DISPLAY 0.489362 (-3212 5358);
PAINT GREEN (-3212 5358);
FORCEPROP 2 LAST CDS_LIB mstr_standard
J 0
(-3150 5350);
DISPLAY 0.723404 (-3150 5350);
PAINT MONO (-3150 5350);
DISPLAY INVISIBLE (-3150 5350);
FORCEPROP 1 LAST BODY_TYPE PLUMBING
J 0
(-3150 5400);
DISPLAY 0.872340 (-3150 5400);
PAINT GREEN (-3150 5400);
DISPLAY INVISIBLE (-3150 5400);
FORCEPROP 1 LAST HDL_TAP TRUE
J 0
(-2825 5225);
DISPLAY 0.872340 (-2825 5225);
DISPLAY INVISIBLE (-2825 5225);
FORCEPROP 1 LAST PATH I174
J 0
(-3152 5350);
DISPLAY 0.872340 (-3152 5350);
PAINT GREEN (-3152 5350);
DISPLAY INVISIBLE (-3152 5350);
FORCEADD TAP..1
(-3150 5300);
FORCEPROP 3 LASTPIN (-3200 5300) SIG_NAME M_K_CPU0_SA_DQ<12>
J 0
(-3190 5310);
DISPLAY 0.659574 (-3190 5310);
PAINT MONO (-3190 5310);
DISPLAY INVISIBLE (-3190 5310);
FORCEPROP 1 LASTPIN (-3200 5300) BN 12
J 0
(-3212 5308);
DISPLAY 0.489362 (-3212 5308);
PAINT GREEN (-3212 5308);
FORCEPROP 2 LAST CDS_LIB mstr_standard
J 0
(-3150 5300);
DISPLAY 0.723404 (-3150 5300);
PAINT MONO (-3150 5300);
DISPLAY INVISIBLE (-3150 5300);
FORCEPROP 1 LAST BODY_TYPE PLUMBING
J 0
(-3150 5350);
DISPLAY 0.872340 (-3150 5350);
PAINT GREEN (-3150 5350);
DISPLAY INVISIBLE (-3150 5350);
FORCEPROP 1 LAST HDL_TAP TRUE
J 0
(-2825 5175);
DISPLAY 0.872340 (-2825 5175);
DISPLAY INVISIBLE (-2825 5175);
FORCEPROP 1 LAST PATH I175
J 0
(-3152 5300);
DISPLAY 0.872340 (-3152 5300);
PAINT GREEN (-3152 5300);
DISPLAY INVISIBLE (-3152 5300);
FORCEADD TAP..1
(-3150 5150);
FORCEPROP 3 LASTPIN (-3200 5150) SIG_NAME M_K_CPU0_SA_DQ<15>
J 0
(-3190 5160);
DISPLAY 0.659574 (-3190 5160);
PAINT MONO (-3190 5160);
DISPLAY INVISIBLE (-3190 5160);
FORCEPROP 1 LASTPIN (-3200 5150) BN 15
J 0
(-3212 5158);
DISPLAY 0.489362 (-3212 5158);
PAINT GREEN (-3212 5158);
FORCEPROP 2 LAST CDS_LIB mstr_standard
J 0
(-3150 5150);
DISPLAY 0.723404 (-3150 5150);
PAINT MONO (-3150 5150);
DISPLAY INVISIBLE (-3150 5150);
FORCEPROP 1 LAST BODY_TYPE PLUMBING
J 0
(-3150 5200);
DISPLAY 0.872340 (-3150 5200);
PAINT GREEN (-3150 5200);
DISPLAY INVISIBLE (-3150 5200);
FORCEPROP 1 LAST HDL_TAP TRUE
J 0
(-2825 5025);
DISPLAY 0.872340 (-2825 5025);
DISPLAY INVISIBLE (-2825 5025);
FORCEPROP 1 LAST PATH I176
J 0
(-3152 5150);
DISPLAY 0.872340 (-3152 5150);
PAINT GREEN (-3152 5150);
DISPLAY INVISIBLE (-3152 5150);
FORCEADD TAP..1
(-3150 5200);
FORCEPROP 3 LASTPIN (-3200 5200) SIG_NAME M_K_CPU0_SA_DQ<14>
J 0
(-3190 5210);
DISPLAY 0.659574 (-3190 5210);
PAINT MONO (-3190 5210);
DISPLAY INVISIBLE (-3190 5210);
FORCEPROP 1 LASTPIN (-3200 5200) BN 14
J 0
(-3212 5208);
DISPLAY 0.489362 (-3212 5208);
PAINT GREEN (-3212 5208);
FORCEPROP 2 LAST CDS_LIB mstr_standard
J 0
(-3150 5200);
DISPLAY 0.723404 (-3150 5200);
PAINT MONO (-3150 5200);
DISPLAY INVISIBLE (-3150 5200);
FORCEPROP 1 LAST BODY_TYPE PLUMBING
J 0
(-3150 5250);
DISPLAY 0.872340 (-3150 5250);
PAINT GREEN (-3150 5250);
DISPLAY INVISIBLE (-3150 5250);
FORCEPROP 1 LAST HDL_TAP TRUE
J 0
(-2825 5075);
DISPLAY 0.872340 (-2825 5075);
DISPLAY INVISIBLE (-2825 5075);
FORCEPROP 1 LAST PATH I177
J 0
(-3152 5200);
DISPLAY 0.872340 (-3152 5200);
PAINT GREEN (-3152 5200);
DISPLAY INVISIBLE (-3152 5200);
FORCEADD TAP..1
(-3150 5000);
FORCEPROP 3 LASTPIN (-3200 5000) SIG_NAME M_K_CPU0_SA_DQ<17>
J 0
(-3190 5010);
DISPLAY 0.659574 (-3190 5010);
PAINT MONO (-3190 5010);
DISPLAY INVISIBLE (-3190 5010);
FORCEPROP 1 LASTPIN (-3200 5000) BN 17
J 0
(-3212 5008);
DISPLAY 0.489362 (-3212 5008);
PAINT GREEN (-3212 5008);
FORCEPROP 2 LAST CDS_LIB mstr_standard
J 0
(-3150 5000);
DISPLAY 0.723404 (-3150 5000);
PAINT MONO (-3150 5000);
DISPLAY INVISIBLE (-3150 5000);
FORCEPROP 1 LAST BODY_TYPE PLUMBING
J 0
(-3150 5050);
DISPLAY 0.872340 (-3150 5050);
PAINT GREEN (-3150 5050);
DISPLAY INVISIBLE (-3150 5050);
FORCEPROP 1 LAST HDL_TAP TRUE
J 0
(-2825 4875);
DISPLAY 0.872340 (-2825 4875);
DISPLAY INVISIBLE (-2825 4875);
FORCEPROP 1 LAST PATH I178
J 0
(-3152 5000);
DISPLAY 0.872340 (-3152 5000);
PAINT GREEN (-3152 5000);
DISPLAY INVISIBLE (-3152 5000);
FORCEADD TAP..1
(-3150 5050);
FORCEPROP 3 LASTPIN (-3200 5050) SIG_NAME M_K_CPU0_SA_DQ<16>
J 0
(-3190 5060);
DISPLAY 0.659574 (-3190 5060);
PAINT MONO (-3190 5060);
DISPLAY INVISIBLE (-3190 5060);
FORCEPROP 1 LASTPIN (-3200 5050) BN 16
J 0
(-3212 5058);
DISPLAY 0.489362 (-3212 5058);
PAINT GREEN (-3212 5058);
FORCEPROP 2 LAST CDS_LIB mstr_standard
J 0
(-3150 5050);
DISPLAY 0.723404 (-3150 5050);
PAINT MONO (-3150 5050);
DISPLAY INVISIBLE (-3150 5050);
FORCEPROP 1 LAST BODY_TYPE PLUMBING
J 0
(-3150 5100);
DISPLAY 0.872340 (-3150 5100);
PAINT GREEN (-3150 5100);
DISPLAY INVISIBLE (-3150 5100);
FORCEPROP 1 LAST HDL_TAP TRUE
J 0
(-2825 4925);
DISPLAY 0.872340 (-2825 4925);
DISPLAY INVISIBLE (-2825 4925);
FORCEPROP 1 LAST PATH I179
J 0
(-3152 5050);
DISPLAY 0.872340 (-3152 5050);
PAINT GREEN (-3152 5050);
DISPLAY INVISIBLE (-3152 5050);
FORCEADD TAP..1
(-3150 4900);
FORCEPROP 3 LASTPIN (-3200 4900) SIG_NAME M_K_CPU0_SA_DQ<19>
J 0
(-3190 4910);
DISPLAY 0.659574 (-3190 4910);
PAINT MONO (-3190 4910);
DISPLAY INVISIBLE (-3190 4910);
FORCEPROP 1 LASTPIN (-3200 4900) BN 19
J 0
(-3212 4908);
DISPLAY 0.489362 (-3212 4908);
PAINT GREEN (-3212 4908);
FORCEPROP 2 LAST CDS_LIB mstr_standard
J 0
(-3150 4900);
DISPLAY 0.723404 (-3150 4900);
PAINT MONO (-3150 4900);
DISPLAY INVISIBLE (-3150 4900);
FORCEPROP 1 LAST BODY_TYPE PLUMBING
J 0
(-3150 4950);
DISPLAY 0.872340 (-3150 4950);
PAINT GREEN (-3150 4950);
DISPLAY INVISIBLE (-3150 4950);
FORCEPROP 1 LAST HDL_TAP TRUE
J 0
(-2825 4775);
DISPLAY 0.872340 (-2825 4775);
DISPLAY INVISIBLE (-2825 4775);
FORCEPROP 1 LAST PATH I180
J 0
(-3152 4900);
DISPLAY 0.872340 (-3152 4900);
PAINT GREEN (-3152 4900);
DISPLAY INVISIBLE (-3152 4900);
FORCEADD TAP..1
(-3150 4950);
FORCEPROP 3 LASTPIN (-3200 4950) SIG_NAME M_K_CPU0_SA_DQ<18>
J 0
(-3190 4960);
DISPLAY 0.659574 (-3190 4960);
PAINT MONO (-3190 4960);
DISPLAY INVISIBLE (-3190 4960);
FORCEPROP 1 LASTPIN (-3200 4950) BN 18
J 0
(-3212 4958);
DISPLAY 0.489362 (-3212 4958);
PAINT GREEN (-3212 4958);
FORCEPROP 2 LAST CDS_LIB mstr_standard
J 0
(-3150 4950);
DISPLAY 0.723404 (-3150 4950);
PAINT MONO (-3150 4950);
DISPLAY INVISIBLE (-3150 4950);
FORCEPROP 1 LAST BODY_TYPE PLUMBING
J 0
(-3150 5000);
DISPLAY 0.872340 (-3150 5000);
PAINT GREEN (-3150 5000);
DISPLAY INVISIBLE (-3150 5000);
FORCEPROP 1 LAST HDL_TAP TRUE
J 0
(-2825 4825);
DISPLAY 0.872340 (-2825 4825);
DISPLAY INVISIBLE (-2825 4825);
FORCEPROP 1 LAST PATH I181
J 0
(-3152 4950);
DISPLAY 0.872340 (-3152 4950);
PAINT GREEN (-3152 4950);
DISPLAY INVISIBLE (-3152 4950);
FORCEADD TAP..1
(-3150 4850);
FORCEPROP 3 LASTPIN (-3200 4850) SIG_NAME M_K_CPU0_SA_DQ<20>
J 0
(-3190 4860);
DISPLAY 0.659574 (-3190 4860);
PAINT MONO (-3190 4860);
DISPLAY INVISIBLE (-3190 4860);
FORCEPROP 1 LASTPIN (-3200 4850) BN 20
J 0
(-3212 4858);
DISPLAY 0.489362 (-3212 4858);
PAINT GREEN (-3212 4858);
FORCEPROP 2 LAST CDS_LIB mstr_standard
J 0
(-3150 4850);
DISPLAY 0.723404 (-3150 4850);
PAINT MONO (-3150 4850);
DISPLAY INVISIBLE (-3150 4850);
FORCEPROP 1 LAST BODY_TYPE PLUMBING
J 0
(-3150 4900);
DISPLAY 0.872340 (-3150 4900);
PAINT GREEN (-3150 4900);
DISPLAY INVISIBLE (-3150 4900);
FORCEPROP 1 LAST HDL_TAP TRUE
J 0
(-2825 4725);
DISPLAY 0.872340 (-2825 4725);
DISPLAY INVISIBLE (-2825 4725);
FORCEPROP 1 LAST PATH I182
J 0
(-3152 4850);
DISPLAY 0.872340 (-3152 4850);
PAINT GREEN (-3152 4850);
DISPLAY INVISIBLE (-3152 4850);
FORCEADD TAP..1
(-3150 4750);
FORCEPROP 3 LASTPIN (-3200 4750) SIG_NAME M_K_CPU0_SA_DQ<22>
J 0
(-3190 4760);
DISPLAY 0.659574 (-3190 4760);
PAINT MONO (-3190 4760);
DISPLAY INVISIBLE (-3190 4760);
FORCEPROP 1 LASTPIN (-3200 4750) BN 22
J 0
(-3212 4758);
DISPLAY 0.489362 (-3212 4758);
PAINT GREEN (-3212 4758);
FORCEPROP 2 LAST CDS_LIB mstr_standard
J 0
(-3150 4750);
DISPLAY 0.723404 (-3150 4750);
PAINT MONO (-3150 4750);
DISPLAY INVISIBLE (-3150 4750);
FORCEPROP 1 LAST BODY_TYPE PLUMBING
J 0
(-3150 4800);
DISPLAY 0.872340 (-3150 4800);
PAINT GREEN (-3150 4800);
DISPLAY INVISIBLE (-3150 4800);
FORCEPROP 1 LAST HDL_TAP TRUE
J 0
(-2825 4625);
DISPLAY 0.872340 (-2825 4625);
DISPLAY INVISIBLE (-2825 4625);
FORCEPROP 1 LAST PATH I183
J 0
(-3152 4750);
DISPLAY 0.872340 (-3152 4750);
PAINT GREEN (-3152 4750);
DISPLAY INVISIBLE (-3152 4750);
FORCEADD TAP..1
(-3150 4800);
FORCEPROP 3 LASTPIN (-3200 4800) SIG_NAME M_K_CPU0_SA_DQ<21>
J 0
(-3190 4810);
DISPLAY 0.659574 (-3190 4810);
PAINT MONO (-3190 4810);
DISPLAY INVISIBLE (-3190 4810);
FORCEPROP 1 LASTPIN (-3200 4800) BN 21
J 0
(-3212 4808);
DISPLAY 0.489362 (-3212 4808);
PAINT GREEN (-3212 4808);
FORCEPROP 2 LAST CDS_LIB mstr_standard
J 0
(-3150 4800);
DISPLAY 0.723404 (-3150 4800);
PAINT MONO (-3150 4800);
DISPLAY INVISIBLE (-3150 4800);
FORCEPROP 1 LAST BODY_TYPE PLUMBING
J 0
(-3150 4850);
DISPLAY 0.872340 (-3150 4850);
PAINT GREEN (-3150 4850);
DISPLAY INVISIBLE (-3150 4850);
FORCEPROP 1 LAST HDL_TAP TRUE
J 0
(-2825 4675);
DISPLAY 0.872340 (-2825 4675);
DISPLAY INVISIBLE (-2825 4675);
FORCEPROP 1 LAST PATH I184
J 0
(-3152 4800);
DISPLAY 0.872340 (-3152 4800);
PAINT GREEN (-3152 4800);
DISPLAY INVISIBLE (-3152 4800);
FORCEADD TAP..1
(-3150 4700);
FORCEPROP 3 LASTPIN (-3200 4700) SIG_NAME M_K_CPU0_SA_DQ<23>
J 0
(-3190 4710);
DISPLAY 0.659574 (-3190 4710);
PAINT MONO (-3190 4710);
DISPLAY INVISIBLE (-3190 4710);
FORCEPROP 1 LASTPIN (-3200 4700) BN 23
J 0
(-3212 4708);
DISPLAY 0.489362 (-3212 4708);
PAINT GREEN (-3212 4708);
FORCEPROP 2 LAST CDS_LIB mstr_standard
J 0
(-3150 4700);
DISPLAY 0.723404 (-3150 4700);
PAINT MONO (-3150 4700);
DISPLAY INVISIBLE (-3150 4700);
FORCEPROP 1 LAST BODY_TYPE PLUMBING
J 0
(-3150 4750);
DISPLAY 0.872340 (-3150 4750);
PAINT GREEN (-3150 4750);
DISPLAY INVISIBLE (-3150 4750);
FORCEPROP 1 LAST HDL_TAP TRUE
J 0
(-2825 4575);
DISPLAY 0.872340 (-2825 4575);
DISPLAY INVISIBLE (-2825 4575);
FORCEPROP 1 LAST PATH I185
J 0
(-3152 4700);
DISPLAY 0.872340 (-3152 4700);
PAINT GREEN (-3152 4700);
DISPLAY INVISIBLE (-3152 4700);
FORCEADD TAP..1
(-3150 4550);
FORCEPROP 3 LASTPIN (-3200 4550) SIG_NAME M_K_CPU0_SA_DQ<25>
J 0
(-3190 4560);
DISPLAY 0.659574 (-3190 4560);
PAINT MONO (-3190 4560);
DISPLAY INVISIBLE (-3190 4560);
FORCEPROP 1 LASTPIN (-3200 4550) BN 25
J 0
(-3212 4558);
DISPLAY 0.489362 (-3212 4558);
PAINT GREEN (-3212 4558);
FORCEPROP 2 LAST CDS_LIB mstr_standard
J 0
(-3150 4550);
DISPLAY 0.723404 (-3150 4550);
PAINT MONO (-3150 4550);
DISPLAY INVISIBLE (-3150 4550);
FORCEPROP 1 LAST BODY_TYPE PLUMBING
J 0
(-3150 4600);
DISPLAY 0.872340 (-3150 4600);
PAINT GREEN (-3150 4600);
DISPLAY INVISIBLE (-3150 4600);
FORCEPROP 1 LAST HDL_TAP TRUE
J 0
(-2825 4425);
DISPLAY 0.872340 (-2825 4425);
DISPLAY INVISIBLE (-2825 4425);
FORCEPROP 1 LAST PATH I186
J 0
(-3152 4550);
DISPLAY 0.872340 (-3152 4550);
PAINT GREEN (-3152 4550);
DISPLAY INVISIBLE (-3152 4550);
FORCEADD TAP..1
(-3150 4600);
FORCEPROP 3 LASTPIN (-3200 4600) SIG_NAME M_K_CPU0_SA_DQ<24>
J 0
(-3190 4610);
DISPLAY 0.659574 (-3190 4610);
PAINT MONO (-3190 4610);
DISPLAY INVISIBLE (-3190 4610);
FORCEPROP 1 LASTPIN (-3200 4600) BN 24
J 0
(-3212 4608);
DISPLAY 0.489362 (-3212 4608);
PAINT GREEN (-3212 4608);
FORCEPROP 2 LAST CDS_LIB mstr_standard
J 0
(-3150 4600);
DISPLAY 0.723404 (-3150 4600);
PAINT MONO (-3150 4600);
DISPLAY INVISIBLE (-3150 4600);
FORCEPROP 1 LAST BODY_TYPE PLUMBING
J 0
(-3150 4650);
DISPLAY 0.872340 (-3150 4650);
PAINT GREEN (-3150 4650);
DISPLAY INVISIBLE (-3150 4650);
FORCEPROP 1 LAST HDL_TAP TRUE
J 0
(-2825 4475);
DISPLAY 0.872340 (-2825 4475);
DISPLAY INVISIBLE (-2825 4475);
FORCEPROP 1 LAST PATH I187
J 0
(-3152 4600);
DISPLAY 0.872340 (-3152 4600);
PAINT GREEN (-3152 4600);
DISPLAY INVISIBLE (-3152 4600);
FORCEADD TAP..1
(-3150 4500);
FORCEPROP 3 LASTPIN (-3200 4500) SIG_NAME M_K_CPU0_SA_DQ<26>
J 0
(-3190 4510);
DISPLAY 0.659574 (-3190 4510);
PAINT MONO (-3190 4510);
DISPLAY INVISIBLE (-3190 4510);
FORCEPROP 1 LASTPIN (-3200 4500) BN 26
J 0
(-3212 4508);
DISPLAY 0.489362 (-3212 4508);
PAINT GREEN (-3212 4508);
FORCEPROP 2 LAST CDS_LIB mstr_standard
J 0
(-3150 4500);
DISPLAY 0.723404 (-3150 4500);
PAINT MONO (-3150 4500);
DISPLAY INVISIBLE (-3150 4500);
FORCEPROP 1 LAST BODY_TYPE PLUMBING
J 0
(-3150 4550);
DISPLAY 0.872340 (-3150 4550);
PAINT GREEN (-3150 4550);
DISPLAY INVISIBLE (-3150 4550);
FORCEPROP 1 LAST HDL_TAP TRUE
J 0
(-2825 4375);
DISPLAY 0.872340 (-2825 4375);
DISPLAY INVISIBLE (-2825 4375);
FORCEPROP 1 LAST PATH I188
J 0
(-3152 4500);
DISPLAY 0.872340 (-3152 4500);
PAINT GREEN (-3152 4500);
DISPLAY INVISIBLE (-3152 4500);
FORCEADD TAP..1
(-3150 4400);
FORCEPROP 3 LASTPIN (-3200 4400) SIG_NAME M_K_CPU0_SA_DQ<28>
J 0
(-3190 4410);
DISPLAY 0.659574 (-3190 4410);
PAINT MONO (-3190 4410);
DISPLAY INVISIBLE (-3190 4410);
FORCEPROP 1 LASTPIN (-3200 4400) BN 28
J 0
(-3212 4408);
DISPLAY 0.489362 (-3212 4408);
PAINT GREEN (-3212 4408);
FORCEPROP 2 LAST CDS_LIB mstr_standard
J 0
(-3150 4400);
DISPLAY 0.723404 (-3150 4400);
PAINT MONO (-3150 4400);
DISPLAY INVISIBLE (-3150 4400);
FORCEPROP 1 LAST BODY_TYPE PLUMBING
J 0
(-3150 4450);
DISPLAY 0.872340 (-3150 4450);
PAINT GREEN (-3150 4450);
DISPLAY INVISIBLE (-3150 4450);
FORCEPROP 1 LAST HDL_TAP TRUE
J 0
(-2825 4275);
DISPLAY 0.872340 (-2825 4275);
DISPLAY INVISIBLE (-2825 4275);
FORCEPROP 1 LAST PATH I189
J 0
(-3152 4400);
DISPLAY 0.872340 (-3152 4400);
PAINT GREEN (-3152 4400);
DISPLAY INVISIBLE (-3152 4400);
FORCEADD TAP..1
(-3150 4450);
FORCEPROP 3 LASTPIN (-3200 4450) SIG_NAME M_K_CPU0_SA_DQ<27>
J 0
(-3190 4460);
DISPLAY 0.659574 (-3190 4460);
PAINT MONO (-3190 4460);
DISPLAY INVISIBLE (-3190 4460);
FORCEPROP 1 LASTPIN (-3200 4450) BN 27
J 0
(-3212 4458);
DISPLAY 0.489362 (-3212 4458);
PAINT GREEN (-3212 4458);
FORCEPROP 2 LAST CDS_LIB mstr_standard
J 0
(-3150 4450);
DISPLAY 0.723404 (-3150 4450);
PAINT MONO (-3150 4450);
DISPLAY INVISIBLE (-3150 4450);
FORCEPROP 1 LAST BODY_TYPE PLUMBING
J 0
(-3150 4500);
DISPLAY 0.872340 (-3150 4500);
PAINT GREEN (-3150 4500);
DISPLAY INVISIBLE (-3150 4500);
FORCEPROP 1 LAST HDL_TAP TRUE
J 0
(-2825 4325);
DISPLAY 0.872340 (-2825 4325);
DISPLAY INVISIBLE (-2825 4325);
FORCEPROP 1 LAST PATH I190
J 0
(-3152 4450);
DISPLAY 0.872340 (-3152 4450);
PAINT GREEN (-3152 4450);
DISPLAY INVISIBLE (-3152 4450);
FORCEADD TAP..1
(-3150 4350);
FORCEPROP 3 LASTPIN (-3200 4350) SIG_NAME M_K_CPU0_SA_DQ<29>
J 0
(-3190 4360);
DISPLAY 0.659574 (-3190 4360);
PAINT MONO (-3190 4360);
DISPLAY INVISIBLE (-3190 4360);
FORCEPROP 1 LASTPIN (-3200 4350) BN 29
J 0
(-3212 4358);
DISPLAY 0.489362 (-3212 4358);
PAINT GREEN (-3212 4358);
FORCEPROP 2 LAST CDS_LIB mstr_standard
J 0
(-3150 4350);
DISPLAY 0.723404 (-3150 4350);
PAINT MONO (-3150 4350);
DISPLAY INVISIBLE (-3150 4350);
FORCEPROP 1 LAST BODY_TYPE PLUMBING
J 0
(-3150 4400);
DISPLAY 0.872340 (-3150 4400);
PAINT GREEN (-3150 4400);
DISPLAY INVISIBLE (-3150 4400);
FORCEPROP 1 LAST HDL_TAP TRUE
J 0
(-2825 4225);
DISPLAY 0.872340 (-2825 4225);
DISPLAY INVISIBLE (-2825 4225);
FORCEPROP 1 LAST PATH I191
J 0
(-3152 4350);
DISPLAY 0.872340 (-3152 4350);
PAINT GREEN (-3152 4350);
DISPLAY INVISIBLE (-3152 4350);
FORCEADD TAP..1
(-3150 4250);
FORCEPROP 3 LASTPIN (-3200 4250) SIG_NAME M_K_CPU0_SA_DQ<31>
J 0
(-3190 4260);
DISPLAY 0.659574 (-3190 4260);
PAINT MONO (-3190 4260);
DISPLAY INVISIBLE (-3190 4260);
FORCEPROP 1 LASTPIN (-3200 4250) BN 31
J 0
(-3212 4258);
DISPLAY 0.489362 (-3212 4258);
PAINT GREEN (-3212 4258);
FORCEPROP 2 LAST CDS_LIB mstr_standard
J 0
(-3150 4250);
DISPLAY 0.723404 (-3150 4250);
PAINT MONO (-3150 4250);
DISPLAY INVISIBLE (-3150 4250);
FORCEPROP 1 LAST BODY_TYPE PLUMBING
J 0
(-3150 4300);
DISPLAY 0.872340 (-3150 4300);
PAINT GREEN (-3150 4300);
DISPLAY INVISIBLE (-3150 4300);
FORCEPROP 1 LAST HDL_TAP TRUE
J 0
(-2825 4125);
DISPLAY 0.872340 (-2825 4125);
DISPLAY INVISIBLE (-2825 4125);
FORCEPROP 1 LAST PATH I192
J 0
(-3152 4250);
DISPLAY 0.872340 (-3152 4250);
PAINT GREEN (-3152 4250);
DISPLAY INVISIBLE (-3152 4250);
FORCEADD TAP..1
(-3150 4300);
FORCEPROP 3 LASTPIN (-3200 4300) SIG_NAME M_K_CPU0_SA_DQ<30>
J 0
(-3190 4310);
DISPLAY 0.659574 (-3190 4310);
PAINT MONO (-3190 4310);
DISPLAY INVISIBLE (-3190 4310);
FORCEPROP 1 LASTPIN (-3200 4300) BN 30
J 0
(-3212 4308);
DISPLAY 0.489362 (-3212 4308);
PAINT GREEN (-3212 4308);
FORCEPROP 2 LAST CDS_LIB mstr_standard
J 0
(-3150 4300);
DISPLAY 0.723404 (-3150 4300);
PAINT MONO (-3150 4300);
DISPLAY INVISIBLE (-3150 4300);
FORCEPROP 1 LAST BODY_TYPE PLUMBING
J 0
(-3150 4350);
DISPLAY 0.872340 (-3150 4350);
PAINT GREEN (-3150 4350);
DISPLAY INVISIBLE (-3150 4350);
FORCEPROP 1 LAST HDL_TAP TRUE
J 0
(-2825 4175);
DISPLAY 0.872340 (-2825 4175);
DISPLAY INVISIBLE (-2825 4175);
FORCEPROP 1 LAST PATH I193
J 0
(-3152 4300);
DISPLAY 0.872340 (-3152 4300);
PAINT GREEN (-3152 4300);
DISPLAY INVISIBLE (-3152 4300);
FORCEADD TAP..1
(-3150 4100);
FORCEPROP 3 LASTPIN (-3200 4100) SIG_NAME M_K_CPU0_SB_DQ<1>
J 0
(-3190 4110);
DISPLAY 0.659574 (-3190 4110);
PAINT MONO (-3190 4110);
DISPLAY INVISIBLE (-3190 4110);
FORCEPROP 1 LASTPIN (-3200 4100) BN 1
J 0
(-3212 4108);
DISPLAY 0.489362 (-3212 4108);
PAINT GREEN (-3212 4108);
FORCEPROP 2 LAST CDS_LIB mstr_standard
J 0
(-3150 4100);
DISPLAY 0.723404 (-3150 4100);
PAINT MONO (-3150 4100);
DISPLAY INVISIBLE (-3150 4100);
FORCEPROP 1 LAST BODY_TYPE PLUMBING
J 0
(-3150 4150);
DISPLAY 0.872340 (-3150 4150);
PAINT GREEN (-3150 4150);
DISPLAY INVISIBLE (-3150 4150);
FORCEPROP 1 LAST HDL_TAP TRUE
J 0
(-2825 3975);
DISPLAY 0.872340 (-2825 3975);
DISPLAY INVISIBLE (-2825 3975);
FORCEPROP 1 LAST PATH I194
J 0
(-3152 4100);
DISPLAY 0.872340 (-3152 4100);
PAINT GREEN (-3152 4100);
DISPLAY INVISIBLE (-3152 4100);
FORCEADD TAP..1
(-3150 4150);
FORCEPROP 3 LASTPIN (-3200 4150) SIG_NAME M_K_CPU0_SB_DQ<0>
J 0
(-3190 4160);
DISPLAY 0.659574 (-3190 4160);
PAINT MONO (-3190 4160);
DISPLAY INVISIBLE (-3190 4160);
FORCEPROP 1 LASTPIN (-3200 4150) BN 0
J 0
(-3212 4158);
DISPLAY 0.489362 (-3212 4158);
PAINT GREEN (-3212 4158);
FORCEPROP 2 LAST CDS_LIB mstr_standard
J 0
(-3150 4150);
DISPLAY 0.723404 (-3150 4150);
PAINT MONO (-3150 4150);
DISPLAY INVISIBLE (-3150 4150);
FORCEPROP 1 LAST BODY_TYPE PLUMBING
J 0
(-3150 4200);
DISPLAY 0.872340 (-3150 4200);
PAINT GREEN (-3150 4200);
DISPLAY INVISIBLE (-3150 4200);
FORCEPROP 1 LAST HDL_TAP TRUE
J 0
(-2825 4025);
DISPLAY 0.872340 (-2825 4025);
DISPLAY INVISIBLE (-2825 4025);
FORCEPROP 1 LAST PATH I195
J 0
(-3152 4150);
DISPLAY 0.872340 (-3152 4150);
PAINT GREEN (-3152 4150);
DISPLAY INVISIBLE (-3152 4150);
FORCEADD OFFPAGE..6
R 2
(-2550 2400);
FORCEPROP 2 LAST $XR0 95 
J 0
(-2336 2400);
DISPLAY 0.638298 (-2336 2400);
PAINT MONO (-2336 2400);
FORCEPROP 2 LAST PATH I196
J 0
(-2325 2450);
DISPLAY 1.021277 (-2325 2450);
DISPLAY INVISIBLE (-2325 2450);
FORCEPROP 1 LAST COMMENT_BODY TRUE
J 2
(-2650 2325);
DISPLAY 0.872340 (-2650 2325);
PAINT GREEN (-2650 2325);
DISPLAY INVISIBLE (-2650 2325);
FORCEPROP 1 LAST OFFPAGE TRUE
J 2
(-2875 2275);
DISPLAY 0.872340 (-2875 2275);
PAINT GREEN (-2875 2275);
DISPLAY INVISIBLE (-2875 2275);
FORCEPROP 2 LAST CDS_LIB mstr_standard
J 2
(-2550 2400);
DISPLAY 0.723404 (-2550 2400);
PAINT MONO (-2550 2400);
DISPLAY INVISIBLE (-2550 2400);
FORCEADD TAP..1
(-3150 4050);
FORCEPROP 3 LASTPIN (-3200 4050) SIG_NAME M_K_CPU0_SB_DQ<2>
J 0
(-3190 4060);
DISPLAY 0.659574 (-3190 4060);
PAINT MONO (-3190 4060);
DISPLAY INVISIBLE (-3190 4060);
FORCEPROP 1 LASTPIN (-3200 4050) BN 2
J 0
(-3212 4058);
DISPLAY 0.489362 (-3212 4058);
PAINT GREEN (-3212 4058);
FORCEPROP 2 LAST CDS_LIB mstr_standard
J 0
(-3150 4050);
DISPLAY 0.723404 (-3150 4050);
PAINT MONO (-3150 4050);
DISPLAY INVISIBLE (-3150 4050);
FORCEPROP 1 LAST BODY_TYPE PLUMBING
J 0
(-3150 4100);
DISPLAY 0.872340 (-3150 4100);
PAINT GREEN (-3150 4100);
DISPLAY INVISIBLE (-3150 4100);
FORCEPROP 1 LAST HDL_TAP TRUE
J 0
(-2825 3925);
DISPLAY 0.872340 (-2825 3925);
DISPLAY INVISIBLE (-2825 3925);
FORCEPROP 1 LAST PATH I197
J 0
(-3152 4050);
DISPLAY 0.872340 (-3152 4050);
PAINT GREEN (-3152 4050);
DISPLAY INVISIBLE (-3152 4050);
FORCEADD TAP..1
(-3150 4000);
FORCEPROP 3 LASTPIN (-3200 4000) SIG_NAME M_K_CPU0_SB_DQ<3>
J 0
(-3190 4010);
DISPLAY 0.659574 (-3190 4010);
PAINT MONO (-3190 4010);
DISPLAY INVISIBLE (-3190 4010);
FORCEPROP 1 LASTPIN (-3200 4000) BN 3
J 0
(-3212 4008);
DISPLAY 0.489362 (-3212 4008);
PAINT GREEN (-3212 4008);
FORCEPROP 2 LAST CDS_LIB mstr_standard
J 0
(-3150 4000);
DISPLAY 0.723404 (-3150 4000);
PAINT MONO (-3150 4000);
DISPLAY INVISIBLE (-3150 4000);
FORCEPROP 1 LAST BODY_TYPE PLUMBING
J 0
(-3150 4050);
DISPLAY 0.872340 (-3150 4050);
PAINT GREEN (-3150 4050);
DISPLAY INVISIBLE (-3150 4050);
FORCEPROP 1 LAST HDL_TAP TRUE
J 0
(-2825 3875);
DISPLAY 0.872340 (-2825 3875);
DISPLAY INVISIBLE (-2825 3875);
FORCEPROP 1 LAST PATH I198
J 0
(-3152 4000);
DISPLAY 0.872340 (-3152 4000);
PAINT GREEN (-3152 4000);
DISPLAY INVISIBLE (-3152 4000);
FORCEADD TAP..1
(-3150 3900);
FORCEPROP 3 LASTPIN (-3200 3900) SIG_NAME M_K_CPU0_SB_DQ<5>
J 0
(-3190 3910);
DISPLAY 0.659574 (-3190 3910);
PAINT MONO (-3190 3910);
DISPLAY INVISIBLE (-3190 3910);
FORCEPROP 1 LASTPIN (-3200 3900) BN 5
J 0
(-3212 3908);
DISPLAY 0.489362 (-3212 3908);
PAINT GREEN (-3212 3908);
FORCEPROP 2 LAST CDS_LIB mstr_standard
J 0
(-3150 3900);
DISPLAY 0.723404 (-3150 3900);
PAINT MONO (-3150 3900);
DISPLAY INVISIBLE (-3150 3900);
FORCEPROP 1 LAST BODY_TYPE PLUMBING
J 0
(-3150 3950);
DISPLAY 0.872340 (-3150 3950);
PAINT GREEN (-3150 3950);
DISPLAY INVISIBLE (-3150 3950);
FORCEPROP 1 LAST HDL_TAP TRUE
J 0
(-2825 3775);
DISPLAY 0.872340 (-2825 3775);
DISPLAY INVISIBLE (-2825 3775);
FORCEPROP 1 LAST PATH I199
J 0
(-3152 3900);
DISPLAY 0.872340 (-3152 3900);
PAINT GREEN (-3152 3900);
DISPLAY INVISIBLE (-3152 3900);
FORCEADD TAP..1
(-3150 3850);
FORCEPROP 3 LASTPIN (-3200 3850) SIG_NAME M_K_CPU0_SB_DQ<6>
J 0
(-3190 3860);
DISPLAY 0.659574 (-3190 3860);
PAINT MONO (-3190 3860);
DISPLAY INVISIBLE (-3190 3860);
FORCEPROP 1 LASTPIN (-3200 3850) BN 6
J 0
(-3212 3858);
DISPLAY 0.489362 (-3212 3858);
PAINT GREEN (-3212 3858);
FORCEPROP 2 LAST CDS_LIB mstr_standard
J 0
(-3150 3850);
DISPLAY 0.723404 (-3150 3850);
PAINT MONO (-3150 3850);
DISPLAY INVISIBLE (-3150 3850);
FORCEPROP 1 LAST BODY_TYPE PLUMBING
J 0
(-3150 3900);
DISPLAY 0.872340 (-3150 3900);
PAINT GREEN (-3150 3900);
DISPLAY INVISIBLE (-3150 3900);
FORCEPROP 1 LAST HDL_TAP TRUE
J 0
(-2825 3725);
DISPLAY 0.872340 (-2825 3725);
DISPLAY INVISIBLE (-2825 3725);
FORCEPROP 1 LAST PATH I200
J 0
(-3152 3850);
DISPLAY 0.872340 (-3152 3850);
PAINT GREEN (-3152 3850);
DISPLAY INVISIBLE (-3152 3850);
FORCEADD TAP..1
(-3150 3950);
FORCEPROP 3 LASTPIN (-3200 3950) SIG_NAME M_K_CPU0_SB_DQ<4>
J 0
(-3190 3960);
DISPLAY 0.659574 (-3190 3960);
PAINT MONO (-3190 3960);
DISPLAY INVISIBLE (-3190 3960);
FORCEPROP 1 LASTPIN (-3200 3950) BN 4
J 0
(-3212 3958);
DISPLAY 0.489362 (-3212 3958);
PAINT GREEN (-3212 3958);
FORCEPROP 2 LAST CDS_LIB mstr_standard
J 0
(-3150 3950);
DISPLAY 0.723404 (-3150 3950);
PAINT MONO (-3150 3950);
DISPLAY INVISIBLE (-3150 3950);
FORCEPROP 1 LAST BODY_TYPE PLUMBING
J 0
(-3150 4000);
DISPLAY 0.872340 (-3150 4000);
PAINT GREEN (-3150 4000);
DISPLAY INVISIBLE (-3150 4000);
FORCEPROP 1 LAST HDL_TAP TRUE
J 0
(-2825 3825);
DISPLAY 0.872340 (-2825 3825);
DISPLAY INVISIBLE (-2825 3825);
FORCEPROP 1 LAST PATH I201
J 0
(-3152 3950);
DISPLAY 0.872340 (-3152 3950);
PAINT GREEN (-3152 3950);
DISPLAY INVISIBLE (-3152 3950);
FORCEADD TAP..1
(-3150 3800);
FORCEPROP 3 LASTPIN (-3200 3800) SIG_NAME M_K_CPU0_SB_DQ<7>
J 0
(-3190 3810);
DISPLAY 0.659574 (-3190 3810);
PAINT MONO (-3190 3810);
DISPLAY INVISIBLE (-3190 3810);
FORCEPROP 1 LASTPIN (-3200 3800) BN 7
J 0
(-3212 3808);
DISPLAY 0.489362 (-3212 3808);
PAINT GREEN (-3212 3808);
FORCEPROP 2 LAST CDS_LIB mstr_standard
J 0
(-3150 3800);
DISPLAY 0.723404 (-3150 3800);
PAINT MONO (-3150 3800);
DISPLAY INVISIBLE (-3150 3800);
FORCEPROP 1 LAST BODY_TYPE PLUMBING
J 0
(-3150 3850);
DISPLAY 0.872340 (-3150 3850);
PAINT GREEN (-3150 3850);
DISPLAY INVISIBLE (-3150 3850);
FORCEPROP 1 LAST HDL_TAP TRUE
J 0
(-2825 3675);
DISPLAY 0.872340 (-2825 3675);
DISPLAY INVISIBLE (-2825 3675);
FORCEPROP 1 LAST PATH I202
J 0
(-3152 3800);
DISPLAY 0.872340 (-3152 3800);
PAINT GREEN (-3152 3800);
DISPLAY INVISIBLE (-3152 3800);
FORCEADD TAP..1
(-3150 3600);
FORCEPROP 3 LASTPIN (-3200 3600) SIG_NAME M_K_CPU0_SB_DQ<10>
J 0
(-3190 3610);
DISPLAY 0.659574 (-3190 3610);
PAINT MONO (-3190 3610);
DISPLAY INVISIBLE (-3190 3610);
FORCEPROP 1 LASTPIN (-3200 3600) BN 10
J 0
(-3212 3608);
DISPLAY 0.489362 (-3212 3608);
PAINT GREEN (-3212 3608);
FORCEPROP 2 LAST CDS_LIB mstr_standard
J 0
(-3150 3600);
DISPLAY 0.723404 (-3150 3600);
PAINT MONO (-3150 3600);
DISPLAY INVISIBLE (-3150 3600);
FORCEPROP 1 LAST BODY_TYPE PLUMBING
J 0
(-3150 3650);
DISPLAY 0.872340 (-3150 3650);
PAINT GREEN (-3150 3650);
DISPLAY INVISIBLE (-3150 3650);
FORCEPROP 1 LAST HDL_TAP TRUE
J 0
(-2825 3475);
DISPLAY 0.872340 (-2825 3475);
DISPLAY INVISIBLE (-2825 3475);
FORCEPROP 1 LAST PATH I203
J 0
(-3152 3600);
DISPLAY 0.872340 (-3152 3600);
PAINT GREEN (-3152 3600);
DISPLAY INVISIBLE (-3152 3600);
FORCEADD TAP..1
(-3150 3650);
FORCEPROP 3 LASTPIN (-3200 3650) SIG_NAME M_K_CPU0_SB_DQ<9>
J 0
(-3190 3660);
DISPLAY 0.659574 (-3190 3660);
PAINT MONO (-3190 3660);
DISPLAY INVISIBLE (-3190 3660);
FORCEPROP 1 LASTPIN (-3200 3650) BN 9
J 0
(-3212 3658);
DISPLAY 0.489362 (-3212 3658);
PAINT GREEN (-3212 3658);
FORCEPROP 2 LAST CDS_LIB mstr_standard
J 0
(-3150 3650);
DISPLAY 0.723404 (-3150 3650);
PAINT MONO (-3150 3650);
DISPLAY INVISIBLE (-3150 3650);
FORCEPROP 1 LAST BODY_TYPE PLUMBING
J 0
(-3150 3700);
DISPLAY 0.872340 (-3150 3700);
PAINT GREEN (-3150 3700);
DISPLAY INVISIBLE (-3150 3700);
FORCEPROP 1 LAST HDL_TAP TRUE
J 0
(-2825 3525);
DISPLAY 0.872340 (-2825 3525);
DISPLAY INVISIBLE (-2825 3525);
FORCEPROP 1 LAST PATH I204
J 0
(-3152 3650);
DISPLAY 0.872340 (-3152 3650);
PAINT GREEN (-3152 3650);
DISPLAY INVISIBLE (-3152 3650);
FORCEADD TAP..1
(-3150 3700);
FORCEPROP 3 LASTPIN (-3200 3700) SIG_NAME M_K_CPU0_SB_DQ<8>
J 0
(-3190 3710);
DISPLAY 0.659574 (-3190 3710);
PAINT MONO (-3190 3710);
DISPLAY INVISIBLE (-3190 3710);
FORCEPROP 1 LASTPIN (-3200 3700) BN 8
J 0
(-3212 3708);
DISPLAY 0.489362 (-3212 3708);
PAINT GREEN (-3212 3708);
FORCEPROP 2 LAST CDS_LIB mstr_standard
J 0
(-3150 3700);
DISPLAY 0.723404 (-3150 3700);
PAINT MONO (-3150 3700);
DISPLAY INVISIBLE (-3150 3700);
FORCEPROP 1 LAST BODY_TYPE PLUMBING
J 0
(-3150 3750);
DISPLAY 0.872340 (-3150 3750);
PAINT GREEN (-3150 3750);
DISPLAY INVISIBLE (-3150 3750);
FORCEPROP 1 LAST HDL_TAP TRUE
J 0
(-2825 3575);
DISPLAY 0.872340 (-2825 3575);
DISPLAY INVISIBLE (-2825 3575);
FORCEPROP 1 LAST PATH I205
J 0
(-3152 3700);
DISPLAY 0.872340 (-3152 3700);
PAINT GREEN (-3152 3700);
DISPLAY INVISIBLE (-3152 3700);
FORCEADD TAP..1
(-3150 3500);
FORCEPROP 3 LASTPIN (-3200 3500) SIG_NAME M_K_CPU0_SB_DQ<12>
J 0
(-3190 3510);
DISPLAY 0.659574 (-3190 3510);
PAINT MONO (-3190 3510);
DISPLAY INVISIBLE (-3190 3510);
FORCEPROP 1 LASTPIN (-3200 3500) BN 12
J 0
(-3212 3508);
DISPLAY 0.489362 (-3212 3508);
PAINT GREEN (-3212 3508);
FORCEPROP 2 LAST CDS_LIB mstr_standard
J 0
(-3150 3500);
DISPLAY 0.723404 (-3150 3500);
PAINT MONO (-3150 3500);
DISPLAY INVISIBLE (-3150 3500);
FORCEPROP 1 LAST BODY_TYPE PLUMBING
J 0
(-3150 3550);
DISPLAY 0.872340 (-3150 3550);
PAINT GREEN (-3150 3550);
DISPLAY INVISIBLE (-3150 3550);
FORCEPROP 1 LAST HDL_TAP TRUE
J 0
(-2825 3375);
DISPLAY 0.872340 (-2825 3375);
DISPLAY INVISIBLE (-2825 3375);
FORCEPROP 1 LAST PATH I206
J 0
(-3152 3500);
DISPLAY 0.872340 (-3152 3500);
PAINT GREEN (-3152 3500);
DISPLAY INVISIBLE (-3152 3500);
FORCEADD TAP..1
(-3150 3550);
FORCEPROP 3 LASTPIN (-3200 3550) SIG_NAME M_K_CPU0_SB_DQ<11>
J 0
(-3190 3560);
DISPLAY 0.659574 (-3190 3560);
PAINT MONO (-3190 3560);
DISPLAY INVISIBLE (-3190 3560);
FORCEPROP 1 LASTPIN (-3200 3550) BN 11
J 0
(-3212 3558);
DISPLAY 0.489362 (-3212 3558);
PAINT GREEN (-3212 3558);
FORCEPROP 2 LAST CDS_LIB mstr_standard
J 0
(-3150 3550);
DISPLAY 0.723404 (-3150 3550);
PAINT MONO (-3150 3550);
DISPLAY INVISIBLE (-3150 3550);
FORCEPROP 1 LAST BODY_TYPE PLUMBING
J 0
(-3150 3600);
DISPLAY 0.872340 (-3150 3600);
PAINT GREEN (-3150 3600);
DISPLAY INVISIBLE (-3150 3600);
FORCEPROP 1 LAST HDL_TAP TRUE
J 0
(-2825 3425);
DISPLAY 0.872340 (-2825 3425);
DISPLAY INVISIBLE (-2825 3425);
FORCEPROP 1 LAST PATH I207
J 0
(-3152 3550);
DISPLAY 0.872340 (-3152 3550);
PAINT GREEN (-3152 3550);
DISPLAY INVISIBLE (-3152 3550);
FORCEADD TAP..1
(-3150 3400);
FORCEPROP 3 LASTPIN (-3200 3400) SIG_NAME M_K_CPU0_SB_DQ<14>
J 0
(-3190 3410);
DISPLAY 0.659574 (-3190 3410);
PAINT MONO (-3190 3410);
DISPLAY INVISIBLE (-3190 3410);
FORCEPROP 1 LASTPIN (-3200 3400) BN 14
J 0
(-3212 3408);
DISPLAY 0.489362 (-3212 3408);
PAINT GREEN (-3212 3408);
FORCEPROP 2 LAST CDS_LIB mstr_standard
J 0
(-3150 3400);
DISPLAY 0.723404 (-3150 3400);
PAINT MONO (-3150 3400);
DISPLAY INVISIBLE (-3150 3400);
FORCEPROP 1 LAST BODY_TYPE PLUMBING
J 0
(-3150 3450);
DISPLAY 0.872340 (-3150 3450);
PAINT GREEN (-3150 3450);
DISPLAY INVISIBLE (-3150 3450);
FORCEPROP 1 LAST HDL_TAP TRUE
J 0
(-2825 3275);
DISPLAY 0.872340 (-2825 3275);
DISPLAY INVISIBLE (-2825 3275);
FORCEPROP 1 LAST PATH I208
J 0
(-3152 3400);
DISPLAY 0.872340 (-3152 3400);
PAINT GREEN (-3152 3400);
DISPLAY INVISIBLE (-3152 3400);
FORCEADD TAP..1
(-3150 3350);
FORCEPROP 3 LASTPIN (-3200 3350) SIG_NAME M_K_CPU0_SB_DQ<15>
J 0
(-3190 3360);
DISPLAY 0.659574 (-3190 3360);
PAINT MONO (-3190 3360);
DISPLAY INVISIBLE (-3190 3360);
FORCEPROP 1 LASTPIN (-3200 3350) BN 15
J 0
(-3212 3358);
DISPLAY 0.489362 (-3212 3358);
PAINT GREEN (-3212 3358);
FORCEPROP 2 LAST CDS_LIB mstr_standard
J 0
(-3150 3350);
DISPLAY 0.723404 (-3150 3350);
PAINT MONO (-3150 3350);
DISPLAY INVISIBLE (-3150 3350);
FORCEPROP 1 LAST BODY_TYPE PLUMBING
J 0
(-3150 3400);
DISPLAY 0.872340 (-3150 3400);
PAINT GREEN (-3150 3400);
DISPLAY INVISIBLE (-3150 3400);
FORCEPROP 1 LAST HDL_TAP TRUE
J 0
(-2825 3225);
DISPLAY 0.872340 (-2825 3225);
DISPLAY INVISIBLE (-2825 3225);
FORCEPROP 1 LAST PATH I209
J 0
(-3152 3350);
DISPLAY 0.872340 (-3152 3350);
PAINT GREEN (-3152 3350);
DISPLAY INVISIBLE (-3152 3350);
FORCEADD TAP..1
(-3150 3450);
FORCEPROP 3 LASTPIN (-3200 3450) SIG_NAME M_K_CPU0_SB_DQ<13>
J 0
(-3190 3460);
DISPLAY 0.659574 (-3190 3460);
PAINT MONO (-3190 3460);
DISPLAY INVISIBLE (-3190 3460);
FORCEPROP 1 LASTPIN (-3200 3450) BN 13
J 0
(-3212 3458);
DISPLAY 0.489362 (-3212 3458);
PAINT GREEN (-3212 3458);
FORCEPROP 2 LAST CDS_LIB mstr_standard
J 0
(-3150 3450);
DISPLAY 0.723404 (-3150 3450);
PAINT MONO (-3150 3450);
DISPLAY INVISIBLE (-3150 3450);
FORCEPROP 1 LAST BODY_TYPE PLUMBING
J 0
(-3150 3500);
DISPLAY 0.872340 (-3150 3500);
PAINT GREEN (-3150 3500);
DISPLAY INVISIBLE (-3150 3500);
FORCEPROP 1 LAST HDL_TAP TRUE
J 0
(-2825 3325);
DISPLAY 0.872340 (-2825 3325);
DISPLAY INVISIBLE (-2825 3325);
FORCEPROP 1 LAST PATH I210
J 0
(-3152 3450);
DISPLAY 0.872340 (-3152 3450);
PAINT GREEN (-3152 3450);
DISPLAY INVISIBLE (-3152 3450);
FORCEADD TAP..1
(-3150 3250);
FORCEPROP 3 LASTPIN (-3200 3250) SIG_NAME M_K_CPU0_SB_DQ<16>
J 0
(-3190 3260);
DISPLAY 0.659574 (-3190 3260);
PAINT MONO (-3190 3260);
DISPLAY INVISIBLE (-3190 3260);
FORCEPROP 1 LASTPIN (-3200 3250) BN 16
J 0
(-3212 3258);
DISPLAY 0.489362 (-3212 3258);
PAINT GREEN (-3212 3258);
FORCEPROP 2 LAST CDS_LIB mstr_standard
J 0
(-3150 3250);
DISPLAY 0.723404 (-3150 3250);
PAINT MONO (-3150 3250);
DISPLAY INVISIBLE (-3150 3250);
FORCEPROP 1 LAST BODY_TYPE PLUMBING
J 0
(-3150 3300);
DISPLAY 0.872340 (-3150 3300);
PAINT GREEN (-3150 3300);
DISPLAY INVISIBLE (-3150 3300);
FORCEPROP 1 LAST HDL_TAP TRUE
J 0
(-2825 3125);
DISPLAY 0.872340 (-2825 3125);
DISPLAY INVISIBLE (-2825 3125);
FORCEPROP 1 LAST PATH I211
J 0
(-3152 3250);
DISPLAY 0.872340 (-3152 3250);
PAINT GREEN (-3152 3250);
DISPLAY INVISIBLE (-3152 3250);
FORCEADD TAP..1
(-3150 3200);
FORCEPROP 3 LASTPIN (-3200 3200) SIG_NAME M_K_CPU0_SB_DQ<17>
J 0
(-3190 3210);
DISPLAY 0.659574 (-3190 3210);
PAINT MONO (-3190 3210);
DISPLAY INVISIBLE (-3190 3210);
FORCEPROP 1 LASTPIN (-3200 3200) BN 17
J 0
(-3212 3208);
DISPLAY 0.489362 (-3212 3208);
PAINT GREEN (-3212 3208);
FORCEPROP 2 LAST CDS_LIB mstr_standard
J 0
(-3150 3200);
DISPLAY 0.723404 (-3150 3200);
PAINT MONO (-3150 3200);
DISPLAY INVISIBLE (-3150 3200);
FORCEPROP 1 LAST BODY_TYPE PLUMBING
J 0
(-3150 3250);
DISPLAY 0.872340 (-3150 3250);
PAINT GREEN (-3150 3250);
DISPLAY INVISIBLE (-3150 3250);
FORCEPROP 1 LAST HDL_TAP TRUE
J 0
(-2825 3075);
DISPLAY 0.872340 (-2825 3075);
DISPLAY INVISIBLE (-2825 3075);
FORCEPROP 1 LAST PATH I212
J 0
(-3152 3200);
DISPLAY 0.872340 (-3152 3200);
PAINT GREEN (-3152 3200);
DISPLAY INVISIBLE (-3152 3200);
FORCEADD TAP..1
(-3150 3100);
FORCEPROP 3 LASTPIN (-3200 3100) SIG_NAME M_K_CPU0_SB_DQ<19>
J 0
(-3190 3110);
DISPLAY 0.659574 (-3190 3110);
PAINT MONO (-3190 3110);
DISPLAY INVISIBLE (-3190 3110);
FORCEPROP 1 LASTPIN (-3200 3100) BN 19
J 0
(-3212 3108);
DISPLAY 0.489362 (-3212 3108);
PAINT GREEN (-3212 3108);
FORCEPROP 2 LAST CDS_LIB mstr_standard
J 0
(-3150 3100);
DISPLAY 0.723404 (-3150 3100);
PAINT MONO (-3150 3100);
DISPLAY INVISIBLE (-3150 3100);
FORCEPROP 1 LAST BODY_TYPE PLUMBING
J 0
(-3150 3150);
DISPLAY 0.872340 (-3150 3150);
PAINT GREEN (-3150 3150);
DISPLAY INVISIBLE (-3150 3150);
FORCEPROP 1 LAST HDL_TAP TRUE
J 0
(-2825 2975);
DISPLAY 0.872340 (-2825 2975);
DISPLAY INVISIBLE (-2825 2975);
FORCEPROP 1 LAST PATH I213
J 0
(-3152 3100);
DISPLAY 0.872340 (-3152 3100);
PAINT GREEN (-3152 3100);
DISPLAY INVISIBLE (-3152 3100);
FORCEADD TAP..1
(-3150 3150);
FORCEPROP 3 LASTPIN (-3200 3150) SIG_NAME M_K_CPU0_SB_DQ<18>
J 0
(-3190 3160);
DISPLAY 0.659574 (-3190 3160);
PAINT MONO (-3190 3160);
DISPLAY INVISIBLE (-3190 3160);
FORCEPROP 1 LASTPIN (-3200 3150) BN 18
J 0
(-3212 3158);
DISPLAY 0.489362 (-3212 3158);
PAINT GREEN (-3212 3158);
FORCEPROP 2 LAST CDS_LIB mstr_standard
J 0
(-3150 3150);
DISPLAY 0.723404 (-3150 3150);
PAINT MONO (-3150 3150);
DISPLAY INVISIBLE (-3150 3150);
FORCEPROP 1 LAST BODY_TYPE PLUMBING
J 0
(-3150 3200);
DISPLAY 0.872340 (-3150 3200);
PAINT GREEN (-3150 3200);
DISPLAY INVISIBLE (-3150 3200);
FORCEPROP 1 LAST HDL_TAP TRUE
J 0
(-2825 3025);
DISPLAY 0.872340 (-2825 3025);
DISPLAY INVISIBLE (-2825 3025);
FORCEPROP 1 LAST PATH I214
J 0
(-3152 3150);
DISPLAY 0.872340 (-3152 3150);
PAINT GREEN (-3152 3150);
DISPLAY INVISIBLE (-3152 3150);
FORCEADD TAP..1
(-3150 3000);
FORCEPROP 3 LASTPIN (-3200 3000) SIG_NAME M_K_CPU0_SB_DQ<21>
J 0
(-3190 3010);
DISPLAY 0.659574 (-3190 3010);
PAINT MONO (-3190 3010);
DISPLAY INVISIBLE (-3190 3010);
FORCEPROP 1 LASTPIN (-3200 3000) BN 21
J 0
(-3212 3008);
DISPLAY 0.489362 (-3212 3008);
PAINT GREEN (-3212 3008);
FORCEPROP 2 LAST CDS_LIB mstr_standard
J 0
(-3150 3000);
DISPLAY 0.723404 (-3150 3000);
PAINT MONO (-3150 3000);
DISPLAY INVISIBLE (-3150 3000);
FORCEPROP 1 LAST BODY_TYPE PLUMBING
J 0
(-3150 3050);
DISPLAY 0.872340 (-3150 3050);
PAINT GREEN (-3150 3050);
DISPLAY INVISIBLE (-3150 3050);
FORCEPROP 1 LAST HDL_TAP TRUE
J 0
(-2825 2875);
DISPLAY 0.872340 (-2825 2875);
DISPLAY INVISIBLE (-2825 2875);
FORCEPROP 1 LAST PATH I215
J 0
(-3152 3000);
DISPLAY 0.872340 (-3152 3000);
PAINT GREEN (-3152 3000);
DISPLAY INVISIBLE (-3152 3000);
FORCEADD TAP..1
(-3150 3050);
FORCEPROP 3 LASTPIN (-3200 3050) SIG_NAME M_K_CPU0_SB_DQ<20>
J 0
(-3190 3060);
DISPLAY 0.659574 (-3190 3060);
PAINT MONO (-3190 3060);
DISPLAY INVISIBLE (-3190 3060);
FORCEPROP 1 LASTPIN (-3200 3050) BN 20
J 0
(-3212 3058);
DISPLAY 0.489362 (-3212 3058);
PAINT GREEN (-3212 3058);
FORCEPROP 2 LAST CDS_LIB mstr_standard
J 0
(-3150 3050);
DISPLAY 0.723404 (-3150 3050);
PAINT MONO (-3150 3050);
DISPLAY INVISIBLE (-3150 3050);
FORCEPROP 1 LAST BODY_TYPE PLUMBING
J 0
(-3150 3100);
DISPLAY 0.872340 (-3150 3100);
PAINT GREEN (-3150 3100);
DISPLAY INVISIBLE (-3150 3100);
FORCEPROP 1 LAST HDL_TAP TRUE
J 0
(-2825 2925);
DISPLAY 0.872340 (-2825 2925);
DISPLAY INVISIBLE (-2825 2925);
FORCEPROP 1 LAST PATH I216
J 0
(-3152 3050);
DISPLAY 0.872340 (-3152 3050);
PAINT GREEN (-3152 3050);
DISPLAY INVISIBLE (-3152 3050);
FORCEADD TAP..1
(-3150 2950);
FORCEPROP 3 LASTPIN (-3200 2950) SIG_NAME M_K_CPU0_SB_DQ<22>
J 0
(-3190 2960);
DISPLAY 0.659574 (-3190 2960);
PAINT MONO (-3190 2960);
DISPLAY INVISIBLE (-3190 2960);
FORCEPROP 1 LASTPIN (-3200 2950) BN 22
J 0
(-3212 2958);
DISPLAY 0.489362 (-3212 2958);
PAINT GREEN (-3212 2958);
FORCEPROP 2 LAST CDS_LIB mstr_standard
J 0
(-3150 2950);
DISPLAY 0.723404 (-3150 2950);
PAINT MONO (-3150 2950);
DISPLAY INVISIBLE (-3150 2950);
FORCEPROP 1 LAST BODY_TYPE PLUMBING
J 0
(-3150 3000);
DISPLAY 0.872340 (-3150 3000);
PAINT GREEN (-3150 3000);
DISPLAY INVISIBLE (-3150 3000);
FORCEPROP 1 LAST HDL_TAP TRUE
J 0
(-2825 2825);
DISPLAY 0.872340 (-2825 2825);
DISPLAY INVISIBLE (-2825 2825);
FORCEPROP 1 LAST PATH I217
J 0
(-3152 2950);
DISPLAY 0.872340 (-3152 2950);
PAINT GREEN (-3152 2950);
DISPLAY INVISIBLE (-3152 2950);
FORCEADD TAP..1
(-3150 2900);
FORCEPROP 3 LASTPIN (-3200 2900) SIG_NAME M_K_CPU0_SB_DQ<23>
J 0
(-3190 2910);
DISPLAY 0.659574 (-3190 2910);
PAINT MONO (-3190 2910);
DISPLAY INVISIBLE (-3190 2910);
FORCEPROP 1 LASTPIN (-3200 2900) BN 23
J 0
(-3212 2908);
DISPLAY 0.489362 (-3212 2908);
PAINT GREEN (-3212 2908);
FORCEPROP 2 LAST CDS_LIB mstr_standard
J 0
(-3150 2900);
DISPLAY 0.723404 (-3150 2900);
PAINT MONO (-3150 2900);
DISPLAY INVISIBLE (-3150 2900);
FORCEPROP 1 LAST BODY_TYPE PLUMBING
J 0
(-3150 2950);
DISPLAY 0.872340 (-3150 2950);
PAINT GREEN (-3150 2950);
DISPLAY INVISIBLE (-3150 2950);
FORCEPROP 1 LAST HDL_TAP TRUE
J 0
(-2825 2775);
DISPLAY 0.872340 (-2825 2775);
DISPLAY INVISIBLE (-2825 2775);
FORCEPROP 1 LAST PATH I218
J 0
(-3152 2900);
DISPLAY 0.872340 (-3152 2900);
PAINT GREEN (-3152 2900);
DISPLAY INVISIBLE (-3152 2900);
FORCEADD TAP..1
(-3150 2800);
FORCEPROP 3 LASTPIN (-3200 2800) SIG_NAME M_K_CPU0_SB_DQ<24>
J 0
(-3190 2810);
DISPLAY 0.659574 (-3190 2810);
PAINT MONO (-3190 2810);
DISPLAY INVISIBLE (-3190 2810);
FORCEPROP 1 LASTPIN (-3200 2800) BN 24
J 0
(-3212 2808);
DISPLAY 0.489362 (-3212 2808);
PAINT GREEN (-3212 2808);
FORCEPROP 2 LAST CDS_LIB mstr_standard
J 0
(-3150 2800);
DISPLAY 0.723404 (-3150 2800);
PAINT MONO (-3150 2800);
DISPLAY INVISIBLE (-3150 2800);
FORCEPROP 1 LAST BODY_TYPE PLUMBING
J 0
(-3150 2850);
DISPLAY 0.872340 (-3150 2850);
PAINT GREEN (-3150 2850);
DISPLAY INVISIBLE (-3150 2850);
FORCEPROP 1 LAST HDL_TAP TRUE
J 0
(-2825 2675);
DISPLAY 0.872340 (-2825 2675);
DISPLAY INVISIBLE (-2825 2675);
FORCEPROP 1 LAST PATH I219
J 0
(-3152 2800);
DISPLAY 0.872340 (-3152 2800);
PAINT GREEN (-3152 2800);
DISPLAY INVISIBLE (-3152 2800);
FORCEADD TAP..1
(-3150 2750);
FORCEPROP 3 LASTPIN (-3200 2750) SIG_NAME M_K_CPU0_SB_DQ<25>
J 0
(-3190 2760);
DISPLAY 0.659574 (-3190 2760);
PAINT MONO (-3190 2760);
DISPLAY INVISIBLE (-3190 2760);
FORCEPROP 1 LASTPIN (-3200 2750) BN 25
J 0
(-3212 2758);
DISPLAY 0.489362 (-3212 2758);
PAINT GREEN (-3212 2758);
FORCEPROP 2 LAST CDS_LIB mstr_standard
J 0
(-3150 2750);
DISPLAY 0.723404 (-3150 2750);
PAINT MONO (-3150 2750);
DISPLAY INVISIBLE (-3150 2750);
FORCEPROP 1 LAST BODY_TYPE PLUMBING
J 0
(-3150 2800);
DISPLAY 0.872340 (-3150 2800);
PAINT GREEN (-3150 2800);
DISPLAY INVISIBLE (-3150 2800);
FORCEPROP 1 LAST HDL_TAP TRUE
J 0
(-2825 2625);
DISPLAY 0.872340 (-2825 2625);
DISPLAY INVISIBLE (-2825 2625);
FORCEPROP 1 LAST PATH I220
J 0
(-3152 2750);
DISPLAY 0.872340 (-3152 2750);
PAINT GREEN (-3152 2750);
DISPLAY INVISIBLE (-3152 2750);
FORCEADD TAP..1
(-3150 2700);
FORCEPROP 3 LASTPIN (-3200 2700) SIG_NAME M_K_CPU0_SB_DQ<26>
J 0
(-3190 2710);
DISPLAY 0.659574 (-3190 2710);
PAINT MONO (-3190 2710);
DISPLAY INVISIBLE (-3190 2710);
FORCEPROP 1 LASTPIN (-3200 2700) BN 26
J 0
(-3212 2708);
DISPLAY 0.489362 (-3212 2708);
PAINT GREEN (-3212 2708);
FORCEPROP 2 LAST CDS_LIB mstr_standard
J 0
(-3150 2700);
DISPLAY 0.723404 (-3150 2700);
PAINT MONO (-3150 2700);
DISPLAY INVISIBLE (-3150 2700);
FORCEPROP 1 LAST BODY_TYPE PLUMBING
J 0
(-3150 2750);
DISPLAY 0.872340 (-3150 2750);
PAINT GREEN (-3150 2750);
DISPLAY INVISIBLE (-3150 2750);
FORCEPROP 1 LAST HDL_TAP TRUE
J 0
(-2825 2575);
DISPLAY 0.872340 (-2825 2575);
DISPLAY INVISIBLE (-2825 2575);
FORCEPROP 1 LAST PATH I221
J 0
(-3152 2700);
DISPLAY 0.872340 (-3152 2700);
PAINT GREEN (-3152 2700);
DISPLAY INVISIBLE (-3152 2700);
FORCEADD TAP..1
(-3150 2600);
FORCEPROP 3 LASTPIN (-3200 2600) SIG_NAME M_K_CPU0_SB_DQ<28>
J 0
(-3190 2610);
DISPLAY 0.659574 (-3190 2610);
PAINT MONO (-3190 2610);
DISPLAY INVISIBLE (-3190 2610);
FORCEPROP 1 LASTPIN (-3200 2600) BN 28
J 0
(-3212 2608);
DISPLAY 0.489362 (-3212 2608);
PAINT GREEN (-3212 2608);
FORCEPROP 2 LAST CDS_LIB mstr_standard
J 0
(-3150 2600);
DISPLAY 0.723404 (-3150 2600);
PAINT MONO (-3150 2600);
DISPLAY INVISIBLE (-3150 2600);
FORCEPROP 1 LAST BODY_TYPE PLUMBING
J 0
(-3150 2650);
DISPLAY 0.872340 (-3150 2650);
PAINT GREEN (-3150 2650);
DISPLAY INVISIBLE (-3150 2650);
FORCEPROP 1 LAST HDL_TAP TRUE
J 0
(-2825 2475);
DISPLAY 0.872340 (-2825 2475);
DISPLAY INVISIBLE (-2825 2475);
FORCEPROP 1 LAST PATH I222
J 0
(-3152 2600);
DISPLAY 0.872340 (-3152 2600);
PAINT GREEN (-3152 2600);
DISPLAY INVISIBLE (-3152 2600);
FORCEADD TAP..1
(-3150 2650);
FORCEPROP 3 LASTPIN (-3200 2650) SIG_NAME M_K_CPU0_SB_DQ<27>
J 0
(-3190 2660);
DISPLAY 0.659574 (-3190 2660);
PAINT MONO (-3190 2660);
DISPLAY INVISIBLE (-3190 2660);
FORCEPROP 1 LASTPIN (-3200 2650) BN 27
J 0
(-3212 2658);
DISPLAY 0.489362 (-3212 2658);
PAINT GREEN (-3212 2658);
FORCEPROP 2 LAST CDS_LIB mstr_standard
J 0
(-3150 2650);
DISPLAY 0.723404 (-3150 2650);
PAINT MONO (-3150 2650);
DISPLAY INVISIBLE (-3150 2650);
FORCEPROP 1 LAST BODY_TYPE PLUMBING
J 0
(-3150 2700);
DISPLAY 0.872340 (-3150 2700);
PAINT GREEN (-3150 2700);
DISPLAY INVISIBLE (-3150 2700);
FORCEPROP 1 LAST HDL_TAP TRUE
J 0
(-2825 2525);
DISPLAY 0.872340 (-2825 2525);
DISPLAY INVISIBLE (-2825 2525);
FORCEPROP 1 LAST PATH I223
J 0
(-3152 2650);
DISPLAY 0.872340 (-3152 2650);
PAINT GREEN (-3152 2650);
DISPLAY INVISIBLE (-3152 2650);
FORCEADD TAP..1
(-3150 2550);
FORCEPROP 3 LASTPIN (-3200 2550) SIG_NAME M_K_CPU0_SB_DQ<29>
J 0
(-3190 2560);
DISPLAY 0.659574 (-3190 2560);
PAINT MONO (-3190 2560);
DISPLAY INVISIBLE (-3190 2560);
FORCEPROP 1 LASTPIN (-3200 2550) BN 29
J 0
(-3212 2558);
DISPLAY 0.489362 (-3212 2558);
PAINT GREEN (-3212 2558);
FORCEPROP 2 LAST CDS_LIB mstr_standard
J 0
(-3150 2550);
DISPLAY 0.723404 (-3150 2550);
PAINT MONO (-3150 2550);
DISPLAY INVISIBLE (-3150 2550);
FORCEPROP 1 LAST BODY_TYPE PLUMBING
J 0
(-3150 2600);
DISPLAY 0.872340 (-3150 2600);
PAINT GREEN (-3150 2600);
DISPLAY INVISIBLE (-3150 2600);
FORCEPROP 1 LAST HDL_TAP TRUE
J 0
(-2825 2425);
DISPLAY 0.872340 (-2825 2425);
DISPLAY INVISIBLE (-2825 2425);
FORCEPROP 1 LAST PATH I224
J 0
(-3152 2550);
DISPLAY 0.872340 (-3152 2550);
PAINT GREEN (-3152 2550);
DISPLAY INVISIBLE (-3152 2550);
FORCEADD TAP..1
(-3150 2500);
FORCEPROP 3 LASTPIN (-3200 2500) SIG_NAME M_K_CPU0_SB_DQ<30>
J 0
(-3190 2510);
DISPLAY 0.659574 (-3190 2510);
PAINT MONO (-3190 2510);
DISPLAY INVISIBLE (-3190 2510);
FORCEPROP 1 LASTPIN (-3200 2500) BN 30
J 0
(-3212 2508);
DISPLAY 0.489362 (-3212 2508);
PAINT GREEN (-3212 2508);
FORCEPROP 2 LAST CDS_LIB mstr_standard
J 0
(-3150 2500);
DISPLAY 0.723404 (-3150 2500);
PAINT MONO (-3150 2500);
DISPLAY INVISIBLE (-3150 2500);
FORCEPROP 1 LAST BODY_TYPE PLUMBING
J 0
(-3150 2550);
DISPLAY 0.872340 (-3150 2550);
PAINT GREEN (-3150 2550);
DISPLAY INVISIBLE (-3150 2550);
FORCEPROP 1 LAST HDL_TAP TRUE
J 0
(-2825 2375);
DISPLAY 0.872340 (-2825 2375);
DISPLAY INVISIBLE (-2825 2375);
FORCEPROP 1 LAST PATH I225
J 0
(-3152 2500);
DISPLAY 0.872340 (-3152 2500);
PAINT GREEN (-3152 2500);
DISPLAY INVISIBLE (-3152 2500);
FORCEADD TAP..1
(-3150 2450);
FORCEPROP 3 LASTPIN (-3200 2450) SIG_NAME M_K_CPU0_SB_DQ<31>
J 0
(-3190 2460);
DISPLAY 0.659574 (-3190 2460);
PAINT MONO (-3190 2460);
DISPLAY INVISIBLE (-3190 2460);
FORCEPROP 1 LASTPIN (-3200 2450) BN 31
J 0
(-3212 2458);
DISPLAY 0.489362 (-3212 2458);
PAINT GREEN (-3212 2458);
FORCEPROP 2 LAST CDS_LIB mstr_standard
J 0
(-3150 2450);
DISPLAY 0.723404 (-3150 2450);
PAINT MONO (-3150 2450);
DISPLAY INVISIBLE (-3150 2450);
FORCEPROP 1 LAST BODY_TYPE PLUMBING
J 0
(-3150 2500);
DISPLAY 0.872340 (-3150 2500);
PAINT GREEN (-3150 2500);
DISPLAY INVISIBLE (-3150 2500);
FORCEPROP 1 LAST HDL_TAP TRUE
J 0
(-2825 2325);
DISPLAY 0.872340 (-2825 2325);
DISPLAY INVISIBLE (-2825 2325);
FORCEPROP 1 LAST PATH I226
J 0
(-3152 2450);
DISPLAY 0.872340 (-3152 2450);
PAINT GREEN (-3152 2450);
DISPLAY INVISIBLE (-3152 2450);
FORCEADD TAP..1
(-3150 2350);
FORCEPROP 3 LASTPIN (-3200 2350) SIG_NAME M_K_CPU0_SA_CB<0>
J 0
(-3190 2360);
DISPLAY 0.659574 (-3190 2360);
PAINT MONO (-3190 2360);
DISPLAY INVISIBLE (-3190 2360);
FORCEPROP 1 LASTPIN (-3200 2350) BN 0
J 0
(-3212 2358);
DISPLAY 0.489362 (-3212 2358);
PAINT GREEN (-3212 2358);
FORCEPROP 2 LAST CDS_LIB mstr_standard
J 2
(-3150 2350);
DISPLAY 0.723404 (-3150 2350);
PAINT MONO (-3150 2350);
DISPLAY INVISIBLE (-3150 2350);
FORCEPROP 1 LAST BODY_TYPE PLUMBING
J 0
(-3150 2400);
DISPLAY 0.872340 (-3150 2400);
PAINT GREEN (-3150 2400);
DISPLAY INVISIBLE (-3150 2400);
FORCEPROP 1 LAST HDL_TAP TRUE
J 0
(-2825 2225);
DISPLAY 0.872340 (-2825 2225);
DISPLAY INVISIBLE (-2825 2225);
FORCEPROP 1 LAST PATH I227
J 0
(-3152 2350);
DISPLAY 0.872340 (-3152 2350);
PAINT GREEN (-3152 2350);
DISPLAY INVISIBLE (-3152 2350);
FORCEADD TAP..1
(-3150 2300);
FORCEPROP 3 LASTPIN (-3200 2300) SIG_NAME M_K_CPU0_SA_CB<1>
J 0
(-3190 2310);
DISPLAY 0.659574 (-3190 2310);
PAINT MONO (-3190 2310);
DISPLAY INVISIBLE (-3190 2310);
FORCEPROP 1 LASTPIN (-3200 2300) BN 1
J 0
(-3212 2308);
DISPLAY 0.489362 (-3212 2308);
PAINT GREEN (-3212 2308);
FORCEPROP 2 LAST CDS_LIB mstr_standard
J 2
(-3150 2300);
DISPLAY 0.723404 (-3150 2300);
PAINT MONO (-3150 2300);
DISPLAY INVISIBLE (-3150 2300);
FORCEPROP 1 LAST BODY_TYPE PLUMBING
J 0
(-3150 2350);
DISPLAY 0.872340 (-3150 2350);
PAINT GREEN (-3150 2350);
DISPLAY INVISIBLE (-3150 2350);
FORCEPROP 1 LAST HDL_TAP TRUE
J 0
(-2825 2175);
DISPLAY 0.872340 (-2825 2175);
DISPLAY INVISIBLE (-2825 2175);
FORCEPROP 1 LAST PATH I228
J 0
(-3152 2300);
DISPLAY 0.872340 (-3152 2300);
PAINT GREEN (-3152 2300);
DISPLAY INVISIBLE (-3152 2300);
FORCEADD TAP..1
(-3150 2250);
FORCEPROP 3 LASTPIN (-3200 2250) SIG_NAME M_K_CPU0_SA_CB<2>
J 0
(-3190 2260);
DISPLAY 0.659574 (-3190 2260);
PAINT MONO (-3190 2260);
DISPLAY INVISIBLE (-3190 2260);
FORCEPROP 1 LASTPIN (-3200 2250) BN 2
J 0
(-3212 2258);
DISPLAY 0.489362 (-3212 2258);
PAINT GREEN (-3212 2258);
FORCEPROP 2 LAST CDS_LIB mstr_standard
J 2
(-3150 2250);
DISPLAY 0.723404 (-3150 2250);
PAINT MONO (-3150 2250);
DISPLAY INVISIBLE (-3150 2250);
FORCEPROP 1 LAST BODY_TYPE PLUMBING
J 0
(-3150 2300);
DISPLAY 0.872340 (-3150 2300);
PAINT GREEN (-3150 2300);
DISPLAY INVISIBLE (-3150 2300);
FORCEPROP 1 LAST HDL_TAP TRUE
J 0
(-2825 2125);
DISPLAY 0.872340 (-2825 2125);
DISPLAY INVISIBLE (-2825 2125);
FORCEPROP 1 LAST PATH I229
J 0
(-3152 2250);
DISPLAY 0.872340 (-3152 2250);
PAINT GREEN (-3152 2250);
DISPLAY INVISIBLE (-3152 2250);
FORCEADD TAP..1
(-3150 2200);
FORCEPROP 3 LASTPIN (-3200 2200) SIG_NAME M_K_CPU0_SA_CB<3>
J 0
(-3190 2210);
DISPLAY 0.659574 (-3190 2210);
PAINT MONO (-3190 2210);
DISPLAY INVISIBLE (-3190 2210);
FORCEPROP 1 LASTPIN (-3200 2200) BN 3
J 0
(-3212 2208);
DISPLAY 0.489362 (-3212 2208);
PAINT GREEN (-3212 2208);
FORCEPROP 2 LAST CDS_LIB mstr_standard
J 2
(-3150 2200);
DISPLAY 0.723404 (-3150 2200);
PAINT MONO (-3150 2200);
DISPLAY INVISIBLE (-3150 2200);
FORCEPROP 1 LAST BODY_TYPE PLUMBING
J 0
(-3150 2250);
DISPLAY 0.872340 (-3150 2250);
PAINT GREEN (-3150 2250);
DISPLAY INVISIBLE (-3150 2250);
FORCEPROP 1 LAST HDL_TAP TRUE
J 0
(-2825 2075);
DISPLAY 0.872340 (-2825 2075);
DISPLAY INVISIBLE (-2825 2075);
FORCEPROP 1 LAST PATH I230
J 0
(-3152 2200);
DISPLAY 0.872340 (-3152 2200);
PAINT GREEN (-3152 2200);
DISPLAY INVISIBLE (-3152 2200);
FORCEADD TAP..1
(-3150 2050);
FORCEPROP 3 LASTPIN (-3200 2050) SIG_NAME M_K_CPU0_SA_CB<6>
J 0
(-3190 2060);
DISPLAY 0.659574 (-3190 2060);
PAINT MONO (-3190 2060);
DISPLAY INVISIBLE (-3190 2060);
FORCEPROP 1 LASTPIN (-3200 2050) BN 6
J 0
(-3212 2058);
DISPLAY 0.489362 (-3212 2058);
PAINT GREEN (-3212 2058);
FORCEPROP 2 LAST CDS_LIB mstr_standard
J 2
(-3150 2050);
DISPLAY 0.723404 (-3150 2050);
PAINT MONO (-3150 2050);
DISPLAY INVISIBLE (-3150 2050);
FORCEPROP 1 LAST BODY_TYPE PLUMBING
J 0
(-3150 2100);
DISPLAY 0.872340 (-3150 2100);
PAINT GREEN (-3150 2100);
DISPLAY INVISIBLE (-3150 2100);
FORCEPROP 1 LAST HDL_TAP TRUE
J 0
(-2825 1925);
DISPLAY 0.872340 (-2825 1925);
DISPLAY INVISIBLE (-2825 1925);
FORCEPROP 1 LAST PATH I231
J 0
(-3152 2050);
DISPLAY 0.872340 (-3152 2050);
PAINT GREEN (-3152 2050);
DISPLAY INVISIBLE (-3152 2050);
FORCEADD TAP..1
(-3150 2150);
FORCEPROP 3 LASTPIN (-3200 2150) SIG_NAME M_K_CPU0_SA_CB<4>
J 0
(-3190 2160);
DISPLAY 0.659574 (-3190 2160);
PAINT MONO (-3190 2160);
DISPLAY INVISIBLE (-3190 2160);
FORCEPROP 1 LASTPIN (-3200 2150) BN 4
J 0
(-3212 2158);
DISPLAY 0.489362 (-3212 2158);
PAINT GREEN (-3212 2158);
FORCEPROP 2 LAST CDS_LIB mstr_standard
J 2
(-3150 2150);
DISPLAY 0.723404 (-3150 2150);
PAINT MONO (-3150 2150);
DISPLAY INVISIBLE (-3150 2150);
FORCEPROP 1 LAST BODY_TYPE PLUMBING
J 0
(-3150 2200);
DISPLAY 0.872340 (-3150 2200);
PAINT GREEN (-3150 2200);
DISPLAY INVISIBLE (-3150 2200);
FORCEPROP 1 LAST HDL_TAP TRUE
J 0
(-2825 2025);
DISPLAY 0.872340 (-2825 2025);
DISPLAY INVISIBLE (-2825 2025);
FORCEPROP 1 LAST PATH I232
J 0
(-3152 2150);
DISPLAY 0.872340 (-3152 2150);
PAINT GREEN (-3152 2150);
DISPLAY INVISIBLE (-3152 2150);
FORCEADD TAP..1
(-3150 2100);
FORCEPROP 3 LASTPIN (-3200 2100) SIG_NAME M_K_CPU0_SA_CB<5>
J 0
(-3190 2110);
DISPLAY 0.659574 (-3190 2110);
PAINT MONO (-3190 2110);
DISPLAY INVISIBLE (-3190 2110);
FORCEPROP 1 LASTPIN (-3200 2100) BN 5
J 0
(-3212 2108);
DISPLAY 0.489362 (-3212 2108);
PAINT GREEN (-3212 2108);
FORCEPROP 2 LAST CDS_LIB mstr_standard
J 2
(-3150 2100);
DISPLAY 0.723404 (-3150 2100);
PAINT MONO (-3150 2100);
DISPLAY INVISIBLE (-3150 2100);
FORCEPROP 1 LAST BODY_TYPE PLUMBING
J 0
(-3150 2150);
DISPLAY 0.872340 (-3150 2150);
PAINT GREEN (-3150 2150);
DISPLAY INVISIBLE (-3150 2150);
FORCEPROP 1 LAST HDL_TAP TRUE
J 0
(-2825 1975);
DISPLAY 0.872340 (-2825 1975);
DISPLAY INVISIBLE (-2825 1975);
FORCEPROP 1 LAST PATH I233
J 0
(-3152 2100);
DISPLAY 0.872340 (-3152 2100);
PAINT GREEN (-3152 2100);
DISPLAY INVISIBLE (-3152 2100);
FORCEADD OFFPAGE..6
R 2
(-2550 1950);
FORCEPROP 2 LAST $XR0 95 
J 0
(-2336 1950);
DISPLAY 0.638298 (-2336 1950);
PAINT MONO (-2336 1950);
FORCEPROP 2 LAST PATH I234
J 0
(-2325 2000);
DISPLAY 1.021277 (-2325 2000);
DISPLAY INVISIBLE (-2325 2000);
FORCEPROP 1 LAST COMMENT_BODY TRUE
J 2
(-2650 1875);
DISPLAY 0.872340 (-2650 1875);
PAINT GREEN (-2650 1875);
DISPLAY INVISIBLE (-2650 1875);
FORCEPROP 1 LAST OFFPAGE TRUE
J 2
(-2875 1825);
DISPLAY 0.872340 (-2875 1825);
PAINT GREEN (-2875 1825);
DISPLAY INVISIBLE (-2875 1825);
FORCEPROP 2 LAST CDS_LIB mstr_standard
J 2
(-2550 1950);
DISPLAY 0.723404 (-2550 1950);
PAINT MONO (-2550 1950);
DISPLAY INVISIBLE (-2550 1950);
FORCEADD TAP..1
(-3150 2000);
FORCEPROP 3 LASTPIN (-3200 2000) SIG_NAME M_K_CPU0_SA_CB<7>
J 0
(-3190 2010);
DISPLAY 0.659574 (-3190 2010);
PAINT MONO (-3190 2010);
DISPLAY INVISIBLE (-3190 2010);
FORCEPROP 1 LASTPIN (-3200 2000) BN 7
J 0
(-3212 2008);
DISPLAY 0.489362 (-3212 2008);
PAINT GREEN (-3212 2008);
FORCEPROP 2 LAST CDS_LIB mstr_standard
J 2
(-3150 2000);
DISPLAY 0.723404 (-3150 2000);
PAINT MONO (-3150 2000);
DISPLAY INVISIBLE (-3150 2000);
FORCEPROP 1 LAST BODY_TYPE PLUMBING
J 0
(-3150 2050);
DISPLAY 0.872340 (-3150 2050);
PAINT GREEN (-3150 2050);
DISPLAY INVISIBLE (-3150 2050);
FORCEPROP 1 LAST HDL_TAP TRUE
J 0
(-2825 1875);
DISPLAY 0.872340 (-2825 1875);
DISPLAY INVISIBLE (-2825 1875);
FORCEPROP 1 LAST PATH I235
J 0
(-3152 2000);
DISPLAY 0.872340 (-3152 2000);
PAINT GREEN (-3152 2000);
DISPLAY INVISIBLE (-3152 2000);
FORCEADD TAP..1
(-3150 1800);
FORCEPROP 3 LASTPIN (-3200 1800) SIG_NAME M_K_CPU0_SB_CB<2>
J 0
(-3190 1810);
DISPLAY 0.659574 (-3190 1810);
PAINT MONO (-3190 1810);
DISPLAY INVISIBLE (-3190 1810);
FORCEPROP 1 LASTPIN (-3200 1800) BN 2
J 0
(-3212 1808);
DISPLAY 0.489362 (-3212 1808);
PAINT GREEN (-3212 1808);
FORCEPROP 2 LAST CDS_LIB mstr_standard
J 2
(-3150 1800);
DISPLAY 0.723404 (-3150 1800);
PAINT MONO (-3150 1800);
DISPLAY INVISIBLE (-3150 1800);
FORCEPROP 1 LAST BODY_TYPE PLUMBING
J 0
(-3150 1850);
DISPLAY 0.872340 (-3150 1850);
PAINT GREEN (-3150 1850);
DISPLAY INVISIBLE (-3150 1850);
FORCEPROP 1 LAST HDL_TAP TRUE
J 0
(-2825 1675);
DISPLAY 0.872340 (-2825 1675);
DISPLAY INVISIBLE (-2825 1675);
FORCEPROP 1 LAST PATH I236
J 0
(-3152 1800);
DISPLAY 0.872340 (-3152 1800);
PAINT GREEN (-3152 1800);
DISPLAY INVISIBLE (-3152 1800);
FORCEADD TAP..1
(-3150 1850);
FORCEPROP 3 LASTPIN (-3200 1850) SIG_NAME M_K_CPU0_SB_CB<1>
J 0
(-3190 1860);
DISPLAY 0.659574 (-3190 1860);
PAINT MONO (-3190 1860);
DISPLAY INVISIBLE (-3190 1860);
FORCEPROP 1 LASTPIN (-3200 1850) BN 1
J 0
(-3212 1858);
DISPLAY 0.489362 (-3212 1858);
PAINT GREEN (-3212 1858);
FORCEPROP 2 LAST CDS_LIB mstr_standard
J 2
(-3150 1850);
DISPLAY 0.723404 (-3150 1850);
PAINT MONO (-3150 1850);
DISPLAY INVISIBLE (-3150 1850);
FORCEPROP 1 LAST BODY_TYPE PLUMBING
J 0
(-3150 1900);
DISPLAY 0.872340 (-3150 1900);
PAINT GREEN (-3150 1900);
DISPLAY INVISIBLE (-3150 1900);
FORCEPROP 1 LAST HDL_TAP TRUE
J 0
(-2825 1725);
DISPLAY 0.872340 (-2825 1725);
DISPLAY INVISIBLE (-2825 1725);
FORCEPROP 1 LAST PATH I237
J 0
(-3152 1850);
DISPLAY 0.872340 (-3152 1850);
PAINT GREEN (-3152 1850);
DISPLAY INVISIBLE (-3152 1850);
FORCEADD TAP..1
(-3150 1900);
FORCEPROP 3 LASTPIN (-3200 1900) SIG_NAME M_K_CPU0_SB_CB<0>
J 0
(-3190 1910);
DISPLAY 0.659574 (-3190 1910);
PAINT MONO (-3190 1910);
DISPLAY INVISIBLE (-3190 1910);
FORCEPROP 1 LASTPIN (-3200 1900) BN 0
J 0
(-3212 1908);
DISPLAY 0.489362 (-3212 1908);
PAINT GREEN (-3212 1908);
FORCEPROP 2 LAST CDS_LIB mstr_standard
J 2
(-3150 1900);
DISPLAY 0.723404 (-3150 1900);
PAINT MONO (-3150 1900);
DISPLAY INVISIBLE (-3150 1900);
FORCEPROP 1 LAST BODY_TYPE PLUMBING
J 0
(-3150 1950);
DISPLAY 0.872340 (-3150 1950);
PAINT GREEN (-3150 1950);
DISPLAY INVISIBLE (-3150 1950);
FORCEPROP 1 LAST HDL_TAP TRUE
J 0
(-2825 1775);
DISPLAY 0.872340 (-2825 1775);
DISPLAY INVISIBLE (-2825 1775);
FORCEPROP 1 LAST PATH I238
J 0
(-3152 1900);
DISPLAY 0.872340 (-3152 1900);
PAINT GREEN (-3152 1900);
DISPLAY INVISIBLE (-3152 1900);
FORCEADD TAP..1
(-3150 1750);
FORCEPROP 3 LASTPIN (-3200 1750) SIG_NAME M_K_CPU0_SB_CB<3>
J 0
(-3190 1760);
DISPLAY 0.659574 (-3190 1760);
PAINT MONO (-3190 1760);
DISPLAY INVISIBLE (-3190 1760);
FORCEPROP 1 LASTPIN (-3200 1750) BN 3
J 0
(-3212 1758);
DISPLAY 0.489362 (-3212 1758);
PAINT GREEN (-3212 1758);
FORCEPROP 2 LAST CDS_LIB mstr_standard
J 2
(-3150 1750);
DISPLAY 0.723404 (-3150 1750);
PAINT MONO (-3150 1750);
DISPLAY INVISIBLE (-3150 1750);
FORCEPROP 1 LAST BODY_TYPE PLUMBING
J 0
(-3150 1800);
DISPLAY 0.872340 (-3150 1800);
PAINT GREEN (-3150 1800);
DISPLAY INVISIBLE (-3150 1800);
FORCEPROP 1 LAST HDL_TAP TRUE
J 0
(-2825 1625);
DISPLAY 0.872340 (-2825 1625);
DISPLAY INVISIBLE (-2825 1625);
FORCEPROP 1 LAST PATH I239
J 0
(-3152 1750);
DISPLAY 0.872340 (-3152 1750);
PAINT GREEN (-3152 1750);
DISPLAY INVISIBLE (-3152 1750);
FORCEADD TAP..1
(-3150 1700);
FORCEPROP 3 LASTPIN (-3200 1700) SIG_NAME M_K_CPU0_SB_CB<4>
J 0
(-3190 1710);
DISPLAY 0.659574 (-3190 1710);
PAINT MONO (-3190 1710);
DISPLAY INVISIBLE (-3190 1710);
FORCEPROP 1 LASTPIN (-3200 1700) BN 4
J 0
(-3212 1708);
DISPLAY 0.489362 (-3212 1708);
PAINT GREEN (-3212 1708);
FORCEPROP 2 LAST CDS_LIB mstr_standard
J 2
(-3150 1700);
DISPLAY 0.723404 (-3150 1700);
PAINT MONO (-3150 1700);
DISPLAY INVISIBLE (-3150 1700);
FORCEPROP 1 LAST BODY_TYPE PLUMBING
J 0
(-3150 1750);
DISPLAY 0.872340 (-3150 1750);
PAINT GREEN (-3150 1750);
DISPLAY INVISIBLE (-3150 1750);
FORCEPROP 1 LAST HDL_TAP TRUE
J 0
(-2825 1575);
DISPLAY 0.872340 (-2825 1575);
DISPLAY INVISIBLE (-2825 1575);
FORCEPROP 1 LAST PATH I240
J 0
(-3152 1700);
DISPLAY 0.872340 (-3152 1700);
PAINT GREEN (-3152 1700);
DISPLAY INVISIBLE (-3152 1700);
FORCEADD TAP..1
(-3150 1550);
FORCEPROP 3 LASTPIN (-3200 1550) SIG_NAME M_K_CPU0_SB_CB<7>
J 0
(-3190 1560);
DISPLAY 0.659574 (-3190 1560);
PAINT MONO (-3190 1560);
DISPLAY INVISIBLE (-3190 1560);
FORCEPROP 1 LASTPIN (-3200 1550) BN 7
J 0
(-3212 1558);
DISPLAY 0.489362 (-3212 1558);
PAINT GREEN (-3212 1558);
FORCEPROP 2 LAST CDS_LIB mstr_standard
J 2
(-3150 1550);
DISPLAY 0.723404 (-3150 1550);
PAINT MONO (-3150 1550);
DISPLAY INVISIBLE (-3150 1550);
FORCEPROP 1 LAST BODY_TYPE PLUMBING
J 0
(-3150 1600);
DISPLAY 0.872340 (-3150 1600);
PAINT GREEN (-3150 1600);
DISPLAY INVISIBLE (-3150 1600);
FORCEPROP 1 LAST HDL_TAP TRUE
J 0
(-2825 1425);
DISPLAY 0.872340 (-2825 1425);
DISPLAY INVISIBLE (-2825 1425);
FORCEPROP 1 LAST PATH I241
J 0
(-3152 1550);
DISPLAY 0.872340 (-3152 1550);
PAINT GREEN (-3152 1550);
DISPLAY INVISIBLE (-3152 1550);
FORCEADD TAP..1
(-3150 1600);
FORCEPROP 3 LASTPIN (-3200 1600) SIG_NAME M_K_CPU0_SB_CB<6>
J 0
(-3190 1610);
DISPLAY 0.659574 (-3190 1610);
PAINT MONO (-3190 1610);
DISPLAY INVISIBLE (-3190 1610);
FORCEPROP 1 LASTPIN (-3200 1600) BN 6
J 0
(-3212 1608);
DISPLAY 0.489362 (-3212 1608);
PAINT GREEN (-3212 1608);
FORCEPROP 2 LAST CDS_LIB mstr_standard
J 2
(-3150 1600);
DISPLAY 0.723404 (-3150 1600);
PAINT MONO (-3150 1600);
DISPLAY INVISIBLE (-3150 1600);
FORCEPROP 1 LAST BODY_TYPE PLUMBING
J 0
(-3150 1650);
DISPLAY 0.872340 (-3150 1650);
PAINT GREEN (-3150 1650);
DISPLAY INVISIBLE (-3150 1650);
FORCEPROP 1 LAST HDL_TAP TRUE
J 0
(-2825 1475);
DISPLAY 0.872340 (-2825 1475);
DISPLAY INVISIBLE (-2825 1475);
FORCEPROP 1 LAST PATH I242
J 0
(-3152 1600);
DISPLAY 0.872340 (-3152 1600);
PAINT GREEN (-3152 1600);
DISPLAY INVISIBLE (-3152 1600);
FORCEADD TAP..1
(-3150 1650);
FORCEPROP 3 LASTPIN (-3200 1650) SIG_NAME M_K_CPU0_SB_CB<5>
J 0
(-3190 1660);
DISPLAY 0.659574 (-3190 1660);
PAINT MONO (-3190 1660);
DISPLAY INVISIBLE (-3190 1660);
FORCEPROP 1 LASTPIN (-3200 1650) BN 5
J 0
(-3212 1658);
DISPLAY 0.489362 (-3212 1658);
PAINT GREEN (-3212 1658);
FORCEPROP 2 LAST CDS_LIB mstr_standard
J 2
(-3150 1650);
DISPLAY 0.723404 (-3150 1650);
PAINT MONO (-3150 1650);
DISPLAY INVISIBLE (-3150 1650);
FORCEPROP 1 LAST BODY_TYPE PLUMBING
J 0
(-3150 1700);
DISPLAY 0.872340 (-3150 1700);
PAINT GREEN (-3150 1700);
DISPLAY INVISIBLE (-3150 1700);
FORCEPROP 1 LAST HDL_TAP TRUE
J 0
(-2825 1525);
DISPLAY 0.872340 (-2825 1525);
DISPLAY INVISIBLE (-2825 1525);
FORCEPROP 1 LAST PATH I243
J 0
(-3152 1650);
DISPLAY 0.872340 (-3152 1650);
PAINT GREEN (-3152 1650);
DISPLAY INVISIBLE (-3152 1650);
FORCEADD TAP..1
R 2
(-5575 5950);
FORCEPROP 3 LASTPIN (-5525 5950) SIG_NAME M_K_CPU0_SA_DQS_DP<0>
J 0
(-5515 5960);
DISPLAY 0.659574 (-5515 5960);
PAINT MONO (-5515 5960);
DISPLAY INVISIBLE (-5515 5960);
FORCEPROP 1 LASTPIN (-5525 5950) BN 0
J 2
(-5513 5958);
DISPLAY 0.489362 (-5513 5958);
PAINT GREEN (-5513 5958);
FORCEPROP 2 LAST CDS_LIB mstr_standard
J 2
(-5575 5950);
DISPLAY 0.723404 (-5575 5950);
PAINT MONO (-5575 5950);
DISPLAY INVISIBLE (-5575 5950);
FORCEPROP 1 LAST BODY_TYPE PLUMBING
J 2
(-5575 6000);
DISPLAY 0.872340 (-5575 6000);
PAINT GREEN (-5575 6000);
DISPLAY INVISIBLE (-5575 6000);
FORCEPROP 1 LAST HDL_TAP TRUE
J 2
(-5900 5825);
DISPLAY 0.872340 (-5900 5825);
DISPLAY INVISIBLE (-5900 5825);
FORCEPROP 1 LAST PATH I244
J 2
(-5573 5950);
DISPLAY 0.872340 (-5573 5950);
PAINT GREEN (-5573 5950);
DISPLAY INVISIBLE (-5573 5950);
FORCEADD TAP..1
R 2
(-5575 5850);
FORCEPROP 3 LASTPIN (-5525 5850) SIG_NAME M_K_CPU0_SA_DQS_DP<1>
J 0
(-5515 5860);
DISPLAY 0.659574 (-5515 5860);
PAINT MONO (-5515 5860);
DISPLAY INVISIBLE (-5515 5860);
FORCEPROP 1 LASTPIN (-5525 5850) BN 1
J 2
(-5513 5858);
DISPLAY 0.489362 (-5513 5858);
PAINT GREEN (-5513 5858);
FORCEPROP 2 LAST CDS_LIB mstr_standard
J 2
(-5575 5850);
DISPLAY 0.723404 (-5575 5850);
PAINT MONO (-5575 5850);
DISPLAY INVISIBLE (-5575 5850);
FORCEPROP 1 LAST BODY_TYPE PLUMBING
J 2
(-5575 5900);
DISPLAY 0.872340 (-5575 5900);
PAINT GREEN (-5575 5900);
DISPLAY INVISIBLE (-5575 5900);
FORCEPROP 1 LAST HDL_TAP TRUE
J 2
(-5900 5725);
DISPLAY 0.872340 (-5900 5725);
DISPLAY INVISIBLE (-5900 5725);
FORCEPROP 1 LAST PATH I245
J 2
(-5573 5850);
DISPLAY 0.872340 (-5573 5850);
PAINT GREEN (-5573 5850);
DISPLAY INVISIBLE (-5573 5850);
FORCEADD TAP..1
R 2
(-5575 5750);
FORCEPROP 3 LASTPIN (-5525 5750) SIG_NAME M_K_CPU0_SA_DQS_DP<2>
J 0
(-5515 5760);
DISPLAY 0.659574 (-5515 5760);
PAINT MONO (-5515 5760);
DISPLAY INVISIBLE (-5515 5760);
FORCEPROP 1 LASTPIN (-5525 5750) BN 2
J 2
(-5513 5758);
DISPLAY 0.489362 (-5513 5758);
PAINT GREEN (-5513 5758);
FORCEPROP 2 LAST CDS_LIB mstr_standard
J 2
(-5575 5750);
DISPLAY 0.723404 (-5575 5750);
PAINT MONO (-5575 5750);
DISPLAY INVISIBLE (-5575 5750);
FORCEPROP 1 LAST BODY_TYPE PLUMBING
J 2
(-5575 5800);
DISPLAY 0.872340 (-5575 5800);
PAINT GREEN (-5575 5800);
DISPLAY INVISIBLE (-5575 5800);
FORCEPROP 1 LAST HDL_TAP TRUE
J 2
(-5900 5625);
DISPLAY 0.872340 (-5900 5625);
DISPLAY INVISIBLE (-5900 5625);
FORCEPROP 1 LAST PATH I246
J 2
(-5573 5750);
DISPLAY 0.872340 (-5573 5750);
PAINT GREEN (-5573 5750);
DISPLAY INVISIBLE (-5573 5750);
FORCEADD TAP..1
R 2
(-5575 5650);
FORCEPROP 3 LASTPIN (-5525 5650) SIG_NAME M_K_CPU0_SA_DQS_DP<3>
J 0
(-5515 5660);
DISPLAY 0.659574 (-5515 5660);
PAINT MONO (-5515 5660);
DISPLAY INVISIBLE (-5515 5660);
FORCEPROP 1 LASTPIN (-5525 5650) BN 3
J 2
(-5513 5658);
DISPLAY 0.489362 (-5513 5658);
PAINT GREEN (-5513 5658);
FORCEPROP 2 LAST CDS_LIB mstr_standard
J 2
(-5575 5650);
DISPLAY 0.723404 (-5575 5650);
PAINT MONO (-5575 5650);
DISPLAY INVISIBLE (-5575 5650);
FORCEPROP 1 LAST BODY_TYPE PLUMBING
J 2
(-5575 5700);
DISPLAY 0.872340 (-5575 5700);
PAINT GREEN (-5575 5700);
DISPLAY INVISIBLE (-5575 5700);
FORCEPROP 1 LAST HDL_TAP TRUE
J 2
(-5900 5525);
DISPLAY 0.872340 (-5900 5525);
DISPLAY INVISIBLE (-5900 5525);
FORCEPROP 1 LAST PATH I247
J 2
(-5573 5650);
DISPLAY 0.872340 (-5573 5650);
PAINT GREEN (-5573 5650);
DISPLAY INVISIBLE (-5573 5650);
FORCEADD TAP..1
R 2
(-5575 5450);
FORCEPROP 3 LASTPIN (-5525 5450) SIG_NAME M_K_CPU0_SA_DQS_DP<5>
J 0
(-5515 5460);
DISPLAY 0.659574 (-5515 5460);
PAINT MONO (-5515 5460);
DISPLAY INVISIBLE (-5515 5460);
FORCEPROP 1 LASTPIN (-5525 5450) BN 5
J 2
(-5513 5458);
DISPLAY 0.489362 (-5513 5458);
PAINT GREEN (-5513 5458);
FORCEPROP 2 LAST CDS_LIB mstr_standard
J 2
(-5575 5450);
DISPLAY 0.723404 (-5575 5450);
PAINT MONO (-5575 5450);
DISPLAY INVISIBLE (-5575 5450);
FORCEPROP 1 LAST BODY_TYPE PLUMBING
J 2
(-5575 5500);
DISPLAY 0.872340 (-5575 5500);
PAINT GREEN (-5575 5500);
DISPLAY INVISIBLE (-5575 5500);
FORCEPROP 1 LAST HDL_TAP TRUE
J 2
(-5900 5325);
DISPLAY 0.872340 (-5900 5325);
DISPLAY INVISIBLE (-5900 5325);
FORCEPROP 1 LAST PATH I248
J 2
(-5573 5450);
DISPLAY 0.872340 (-5573 5450);
PAINT GREEN (-5573 5450);
DISPLAY INVISIBLE (-5573 5450);
FORCEADD TAP..1
R 2
(-5575 5550);
FORCEPROP 3 LASTPIN (-5525 5550) SIG_NAME M_K_CPU0_SA_DQS_DP<4>
J 0
(-5515 5560);
DISPLAY 0.659574 (-5515 5560);
PAINT MONO (-5515 5560);
DISPLAY INVISIBLE (-5515 5560);
FORCEPROP 1 LASTPIN (-5525 5550) BN 4
J 2
(-5513 5558);
DISPLAY 0.489362 (-5513 5558);
PAINT GREEN (-5513 5558);
FORCEPROP 2 LAST CDS_LIB mstr_standard
J 2
(-5575 5550);
DISPLAY 0.723404 (-5575 5550);
PAINT MONO (-5575 5550);
DISPLAY INVISIBLE (-5575 5550);
FORCEPROP 1 LAST BODY_TYPE PLUMBING
J 2
(-5575 5600);
DISPLAY 0.872340 (-5575 5600);
PAINT GREEN (-5575 5600);
DISPLAY INVISIBLE (-5575 5600);
FORCEPROP 1 LAST HDL_TAP TRUE
J 2
(-5900 5425);
DISPLAY 0.872340 (-5900 5425);
DISPLAY INVISIBLE (-5900 5425);
FORCEPROP 1 LAST PATH I249
J 2
(-5573 5550);
DISPLAY 0.872340 (-5573 5550);
PAINT GREEN (-5573 5550);
DISPLAY INVISIBLE (-5573 5550);
FORCEADD TAP..1
R 2
(-5575 5250);
FORCEPROP 3 LASTPIN (-5525 5250) SIG_NAME M_K_CPU0_SA_DQS_DP<7>
J 0
(-5515 5260);
DISPLAY 0.659574 (-5515 5260);
PAINT MONO (-5515 5260);
DISPLAY INVISIBLE (-5515 5260);
FORCEPROP 1 LASTPIN (-5525 5250) BN 7
J 2
(-5513 5258);
DISPLAY 0.489362 (-5513 5258);
PAINT GREEN (-5513 5258);
FORCEPROP 2 LAST CDS_LIB mstr_standard
J 2
(-5575 5250);
DISPLAY 0.723404 (-5575 5250);
PAINT MONO (-5575 5250);
DISPLAY INVISIBLE (-5575 5250);
FORCEPROP 1 LAST BODY_TYPE PLUMBING
J 2
(-5575 5300);
DISPLAY 0.872340 (-5575 5300);
PAINT GREEN (-5575 5300);
DISPLAY INVISIBLE (-5575 5300);
FORCEPROP 1 LAST HDL_TAP TRUE
J 2
(-5900 5125);
DISPLAY 0.872340 (-5900 5125);
DISPLAY INVISIBLE (-5900 5125);
FORCEPROP 1 LAST PATH I250
J 2
(-5573 5250);
DISPLAY 0.872340 (-5573 5250);
PAINT GREEN (-5573 5250);
DISPLAY INVISIBLE (-5573 5250);
FORCEADD TAP..1
R 2
(-5575 5350);
FORCEPROP 3 LASTPIN (-5525 5350) SIG_NAME M_K_CPU0_SA_DQS_DP<6>
J 0
(-5515 5360);
DISPLAY 0.659574 (-5515 5360);
PAINT MONO (-5515 5360);
DISPLAY INVISIBLE (-5515 5360);
FORCEPROP 1 LASTPIN (-5525 5350) BN 6
J 2
(-5513 5358);
DISPLAY 0.489362 (-5513 5358);
PAINT GREEN (-5513 5358);
FORCEPROP 2 LAST CDS_LIB mstr_standard
J 2
(-5575 5350);
DISPLAY 0.723404 (-5575 5350);
PAINT MONO (-5575 5350);
DISPLAY INVISIBLE (-5575 5350);
FORCEPROP 1 LAST BODY_TYPE PLUMBING
J 2
(-5575 5400);
DISPLAY 0.872340 (-5575 5400);
PAINT GREEN (-5575 5400);
DISPLAY INVISIBLE (-5575 5400);
FORCEPROP 1 LAST HDL_TAP TRUE
J 2
(-5900 5225);
DISPLAY 0.872340 (-5900 5225);
DISPLAY INVISIBLE (-5900 5225);
FORCEPROP 1 LAST PATH I251
J 2
(-5573 5350);
DISPLAY 0.872340 (-5573 5350);
PAINT GREEN (-5573 5350);
DISPLAY INVISIBLE (-5573 5350);
FORCEADD TAP..1
R 2
(-5575 5150);
FORCEPROP 3 LASTPIN (-5525 5150) SIG_NAME M_K_CPU0_SA_DQS_DP<8>
J 0
(-5515 5160);
DISPLAY 0.659574 (-5515 5160);
PAINT MONO (-5515 5160);
DISPLAY INVISIBLE (-5515 5160);
FORCEPROP 1 LASTPIN (-5525 5150) BN 8
J 2
(-5513 5158);
DISPLAY 0.489362 (-5513 5158);
PAINT GREEN (-5513 5158);
FORCEPROP 2 LAST CDS_LIB mstr_standard
J 2
(-5575 5150);
DISPLAY 0.723404 (-5575 5150);
PAINT MONO (-5575 5150);
DISPLAY INVISIBLE (-5575 5150);
FORCEPROP 1 LAST BODY_TYPE PLUMBING
J 2
(-5575 5200);
DISPLAY 0.872340 (-5575 5200);
PAINT GREEN (-5575 5200);
DISPLAY INVISIBLE (-5575 5200);
FORCEPROP 1 LAST HDL_TAP TRUE
J 2
(-5900 5025);
DISPLAY 0.872340 (-5900 5025);
DISPLAY INVISIBLE (-5900 5025);
FORCEPROP 1 LAST PATH I252
J 2
(-5573 5150);
DISPLAY 0.872340 (-5573 5150);
PAINT GREEN (-5573 5150);
DISPLAY INVISIBLE (-5573 5150);
FORCEADD TAP..1
R 2
(-5775 5900);
FORCEPROP 3 LASTPIN (-5725 5900) SIG_NAME M_K_CPU0_SA_DQS_DN<0>
J 0
(-5715 5910);
DISPLAY 0.659574 (-5715 5910);
PAINT MONO (-5715 5910);
DISPLAY INVISIBLE (-5715 5910);
FORCEPROP 1 LASTPIN (-5725 5900) BN 0
J 2
(-5713 5908);
DISPLAY 0.489362 (-5713 5908);
PAINT GREEN (-5713 5908);
FORCEPROP 2 LAST CDS_LIB mstr_standard
J 2
(-5775 5900);
DISPLAY 0.723404 (-5775 5900);
PAINT MONO (-5775 5900);
DISPLAY INVISIBLE (-5775 5900);
FORCEPROP 1 LAST BODY_TYPE PLUMBING
J 2
(-5775 5950);
DISPLAY 0.872340 (-5775 5950);
PAINT GREEN (-5775 5950);
DISPLAY INVISIBLE (-5775 5950);
FORCEPROP 1 LAST HDL_TAP TRUE
J 2
(-6100 5775);
DISPLAY 0.872340 (-6100 5775);
DISPLAY INVISIBLE (-6100 5775);
FORCEPROP 1 LAST PATH I253
J 2
(-5773 5900);
DISPLAY 0.872340 (-5773 5900);
PAINT GREEN (-5773 5900);
DISPLAY INVISIBLE (-5773 5900);
FORCEADD TAP..1
R 2
(-5775 5800);
FORCEPROP 3 LASTPIN (-5725 5800) SIG_NAME M_K_CPU0_SA_DQS_DN<1>
J 0
(-5715 5810);
DISPLAY 0.659574 (-5715 5810);
PAINT MONO (-5715 5810);
DISPLAY INVISIBLE (-5715 5810);
FORCEPROP 1 LASTPIN (-5725 5800) BN 1
J 2
(-5713 5808);
DISPLAY 0.489362 (-5713 5808);
PAINT GREEN (-5713 5808);
FORCEPROP 2 LAST CDS_LIB mstr_standard
J 2
(-5775 5800);
DISPLAY 0.723404 (-5775 5800);
PAINT MONO (-5775 5800);
DISPLAY INVISIBLE (-5775 5800);
FORCEPROP 1 LAST BODY_TYPE PLUMBING
J 2
(-5775 5850);
DISPLAY 0.872340 (-5775 5850);
PAINT GREEN (-5775 5850);
DISPLAY INVISIBLE (-5775 5850);
FORCEPROP 1 LAST HDL_TAP TRUE
J 2
(-6100 5675);
DISPLAY 0.872340 (-6100 5675);
DISPLAY INVISIBLE (-6100 5675);
FORCEPROP 1 LAST PATH I254
J 2
(-5773 5800);
DISPLAY 0.872340 (-5773 5800);
PAINT GREEN (-5773 5800);
DISPLAY INVISIBLE (-5773 5800);
FORCEADD TAP..1
R 2
(-5775 5700);
FORCEPROP 3 LASTPIN (-5725 5700) SIG_NAME M_K_CPU0_SA_DQS_DN<2>
J 0
(-5715 5710);
DISPLAY 0.659574 (-5715 5710);
PAINT MONO (-5715 5710);
DISPLAY INVISIBLE (-5715 5710);
FORCEPROP 1 LASTPIN (-5725 5700) BN 2
J 2
(-5713 5708);
DISPLAY 0.489362 (-5713 5708);
PAINT GREEN (-5713 5708);
FORCEPROP 2 LAST CDS_LIB mstr_standard
J 2
(-5775 5700);
DISPLAY 0.723404 (-5775 5700);
PAINT MONO (-5775 5700);
DISPLAY INVISIBLE (-5775 5700);
FORCEPROP 1 LAST BODY_TYPE PLUMBING
J 2
(-5775 5750);
DISPLAY 0.872340 (-5775 5750);
PAINT GREEN (-5775 5750);
DISPLAY INVISIBLE (-5775 5750);
FORCEPROP 1 LAST HDL_TAP TRUE
J 2
(-6100 5575);
DISPLAY 0.872340 (-6100 5575);
DISPLAY INVISIBLE (-6100 5575);
FORCEPROP 1 LAST PATH I255
J 2
(-5773 5700);
DISPLAY 0.872340 (-5773 5700);
PAINT GREEN (-5773 5700);
DISPLAY INVISIBLE (-5773 5700);
FORCEADD TAP..1
R 2
(-5775 5600);
FORCEPROP 3 LASTPIN (-5725 5600) SIG_NAME M_K_CPU0_SA_DQS_DN<3>
J 0
(-5715 5610);
DISPLAY 0.659574 (-5715 5610);
PAINT MONO (-5715 5610);
DISPLAY INVISIBLE (-5715 5610);
FORCEPROP 1 LASTPIN (-5725 5600) BN 3
J 2
(-5713 5608);
DISPLAY 0.489362 (-5713 5608);
PAINT GREEN (-5713 5608);
FORCEPROP 2 LAST CDS_LIB mstr_standard
J 2
(-5775 5600);
DISPLAY 0.723404 (-5775 5600);
PAINT MONO (-5775 5600);
DISPLAY INVISIBLE (-5775 5600);
FORCEPROP 1 LAST BODY_TYPE PLUMBING
J 2
(-5775 5650);
DISPLAY 0.872340 (-5775 5650);
PAINT GREEN (-5775 5650);
DISPLAY INVISIBLE (-5775 5650);
FORCEPROP 1 LAST HDL_TAP TRUE
J 2
(-6100 5475);
DISPLAY 0.872340 (-6100 5475);
DISPLAY INVISIBLE (-6100 5475);
FORCEPROP 1 LAST PATH I256
J 2
(-5773 5600);
DISPLAY 0.872340 (-5773 5600);
PAINT GREEN (-5773 5600);
DISPLAY INVISIBLE (-5773 5600);
FORCEADD TAP..1
R 2
(-5775 5400);
FORCEPROP 3 LASTPIN (-5725 5400) SIG_NAME M_K_CPU0_SA_DQS_DN<5>
J 0
(-5715 5410);
DISPLAY 0.659574 (-5715 5410);
PAINT MONO (-5715 5410);
DISPLAY INVISIBLE (-5715 5410);
FORCEPROP 1 LASTPIN (-5725 5400) BN 5
J 2
(-5713 5408);
DISPLAY 0.489362 (-5713 5408);
PAINT GREEN (-5713 5408);
FORCEPROP 2 LAST CDS_LIB mstr_standard
J 2
(-5775 5400);
DISPLAY 0.723404 (-5775 5400);
PAINT MONO (-5775 5400);
DISPLAY INVISIBLE (-5775 5400);
FORCEPROP 1 LAST BODY_TYPE PLUMBING
J 2
(-5775 5450);
DISPLAY 0.872340 (-5775 5450);
PAINT GREEN (-5775 5450);
DISPLAY INVISIBLE (-5775 5450);
FORCEPROP 1 LAST HDL_TAP TRUE
J 2
(-6100 5275);
DISPLAY 0.872340 (-6100 5275);
DISPLAY INVISIBLE (-6100 5275);
FORCEPROP 1 LAST PATH I257
J 2
(-5773 5400);
DISPLAY 0.872340 (-5773 5400);
PAINT GREEN (-5773 5400);
DISPLAY INVISIBLE (-5773 5400);
FORCEADD TAP..1
R 2
(-5775 5500);
FORCEPROP 3 LASTPIN (-5725 5500) SIG_NAME M_K_CPU0_SA_DQS_DN<4>
J 0
(-5715 5510);
DISPLAY 0.659574 (-5715 5510);
PAINT MONO (-5715 5510);
DISPLAY INVISIBLE (-5715 5510);
FORCEPROP 1 LASTPIN (-5725 5500) BN 4
J 2
(-5713 5508);
DISPLAY 0.489362 (-5713 5508);
PAINT GREEN (-5713 5508);
FORCEPROP 2 LAST CDS_LIB mstr_standard
J 2
(-5775 5500);
DISPLAY 0.723404 (-5775 5500);
PAINT MONO (-5775 5500);
DISPLAY INVISIBLE (-5775 5500);
FORCEPROP 1 LAST BODY_TYPE PLUMBING
J 2
(-5775 5550);
DISPLAY 0.872340 (-5775 5550);
PAINT GREEN (-5775 5550);
DISPLAY INVISIBLE (-5775 5550);
FORCEPROP 1 LAST HDL_TAP TRUE
J 2
(-6100 5375);
DISPLAY 0.872340 (-6100 5375);
DISPLAY INVISIBLE (-6100 5375);
FORCEPROP 1 LAST PATH I258
J 2
(-5773 5500);
DISPLAY 0.872340 (-5773 5500);
PAINT GREEN (-5773 5500);
DISPLAY INVISIBLE (-5773 5500);
FORCEADD TAP..1
R 2
(-5775 5300);
FORCEPROP 3 LASTPIN (-5725 5300) SIG_NAME M_K_CPU0_SA_DQS_DN<6>
J 0
(-5715 5310);
DISPLAY 0.659574 (-5715 5310);
PAINT MONO (-5715 5310);
DISPLAY INVISIBLE (-5715 5310);
FORCEPROP 1 LASTPIN (-5725 5300) BN 6
J 2
(-5713 5308);
DISPLAY 0.489362 (-5713 5308);
PAINT GREEN (-5713 5308);
FORCEPROP 2 LAST CDS_LIB mstr_standard
J 2
(-5775 5300);
DISPLAY 0.723404 (-5775 5300);
PAINT MONO (-5775 5300);
DISPLAY INVISIBLE (-5775 5300);
FORCEPROP 1 LAST BODY_TYPE PLUMBING
J 2
(-5775 5350);
DISPLAY 0.872340 (-5775 5350);
PAINT GREEN (-5775 5350);
DISPLAY INVISIBLE (-5775 5350);
FORCEPROP 1 LAST HDL_TAP TRUE
J 2
(-6100 5175);
DISPLAY 0.872340 (-6100 5175);
DISPLAY INVISIBLE (-6100 5175);
FORCEPROP 1 LAST PATH I259
J 2
(-5773 5300);
DISPLAY 0.872340 (-5773 5300);
PAINT GREEN (-5773 5300);
DISPLAY INVISIBLE (-5773 5300);
FORCEADD TAP..1
R 2
(-5775 5200);
FORCEPROP 3 LASTPIN (-5725 5200) SIG_NAME M_K_CPU0_SA_DQS_DN<7>
J 0
(-5715 5210);
DISPLAY 0.659574 (-5715 5210);
PAINT MONO (-5715 5210);
DISPLAY INVISIBLE (-5715 5210);
FORCEPROP 1 LASTPIN (-5725 5200) BN 7
J 2
(-5713 5208);
DISPLAY 0.489362 (-5713 5208);
PAINT GREEN (-5713 5208);
FORCEPROP 2 LAST CDS_LIB mstr_standard
J 2
(-5775 5200);
DISPLAY 0.723404 (-5775 5200);
PAINT MONO (-5775 5200);
DISPLAY INVISIBLE (-5775 5200);
FORCEPROP 1 LAST BODY_TYPE PLUMBING
J 2
(-5775 5250);
DISPLAY 0.872340 (-5775 5250);
PAINT GREEN (-5775 5250);
DISPLAY INVISIBLE (-5775 5250);
FORCEPROP 1 LAST HDL_TAP TRUE
J 2
(-6100 5075);
DISPLAY 0.872340 (-6100 5075);
DISPLAY INVISIBLE (-6100 5075);
FORCEPROP 1 LAST PATH I260
J 2
(-5773 5200);
DISPLAY 0.872340 (-5773 5200);
PAINT GREEN (-5773 5200);
DISPLAY INVISIBLE (-5773 5200);
FORCEADD TAP..1
R 2
(-5575 4900);
FORCEPROP 3 LASTPIN (-5525 4900) SIG_NAME M_K_CPU0_SB_DQS_DP<0>
J 0
(-5515 4910);
DISPLAY 0.659574 (-5515 4910);
PAINT MONO (-5515 4910);
DISPLAY INVISIBLE (-5515 4910);
FORCEPROP 1 LASTPIN (-5525 4900) BN 0
J 2
(-5513 4908);
DISPLAY 0.489362 (-5513 4908);
PAINT GREEN (-5513 4908);
FORCEPROP 2 LAST CDS_LIB mstr_standard
J 2
(-5575 4900);
DISPLAY 0.723404 (-5575 4900);
PAINT MONO (-5575 4900);
DISPLAY INVISIBLE (-5575 4900);
FORCEPROP 1 LAST BODY_TYPE PLUMBING
J 2
(-5575 4950);
DISPLAY 0.872340 (-5575 4950);
PAINT GREEN (-5575 4950);
DISPLAY INVISIBLE (-5575 4950);
FORCEPROP 1 LAST HDL_TAP TRUE
J 2
(-5900 4775);
DISPLAY 0.872340 (-5900 4775);
DISPLAY INVISIBLE (-5900 4775);
FORCEPROP 1 LAST PATH I261
J 2
(-5573 4900);
DISPLAY 0.872340 (-5573 4900);
PAINT GREEN (-5573 4900);
DISPLAY INVISIBLE (-5573 4900);
FORCEADD TAP..1
R 2
(-5575 5050);
FORCEPROP 3 LASTPIN (-5525 5050) SIG_NAME M_K_CPU0_SA_DQS_DP<9>
J 0
(-5515 5060);
DISPLAY 0.659574 (-5515 5060);
PAINT MONO (-5515 5060);
DISPLAY INVISIBLE (-5515 5060);
FORCEPROP 1 LASTPIN (-5525 5050) BN 9
J 2
(-5513 5058);
DISPLAY 0.489362 (-5513 5058);
PAINT GREEN (-5513 5058);
FORCEPROP 2 LAST CDS_LIB mstr_standard
J 2
(-5575 5050);
DISPLAY 0.723404 (-5575 5050);
PAINT MONO (-5575 5050);
DISPLAY INVISIBLE (-5575 5050);
FORCEPROP 1 LAST BODY_TYPE PLUMBING
J 2
(-5575 5100);
DISPLAY 0.872340 (-5575 5100);
PAINT GREEN (-5575 5100);
DISPLAY INVISIBLE (-5575 5100);
FORCEPROP 1 LAST HDL_TAP TRUE
J 2
(-5900 4925);
DISPLAY 0.872340 (-5900 4925);
DISPLAY INVISIBLE (-5900 4925);
FORCEPROP 1 LAST PATH I262
J 2
(-5573 5050);
DISPLAY 0.872340 (-5573 5050);
PAINT GREEN (-5573 5050);
DISPLAY INVISIBLE (-5573 5050);
FORCEADD TAP..1
R 2
(-5575 4800);
FORCEPROP 3 LASTPIN (-5525 4800) SIG_NAME M_K_CPU0_SB_DQS_DP<1>
J 0
(-5515 4810);
DISPLAY 0.659574 (-5515 4810);
PAINT MONO (-5515 4810);
DISPLAY INVISIBLE (-5515 4810);
FORCEPROP 1 LASTPIN (-5525 4800) BN 1
J 2
(-5513 4808);
DISPLAY 0.489362 (-5513 4808);
PAINT GREEN (-5513 4808);
FORCEPROP 2 LAST CDS_LIB mstr_standard
J 2
(-5575 4800);
DISPLAY 0.723404 (-5575 4800);
PAINT MONO (-5575 4800);
DISPLAY INVISIBLE (-5575 4800);
FORCEPROP 1 LAST BODY_TYPE PLUMBING
J 2
(-5575 4850);
DISPLAY 0.872340 (-5575 4850);
PAINT GREEN (-5575 4850);
DISPLAY INVISIBLE (-5575 4850);
FORCEPROP 1 LAST HDL_TAP TRUE
J 2
(-5900 4675);
DISPLAY 0.872340 (-5900 4675);
DISPLAY INVISIBLE (-5900 4675);
FORCEPROP 1 LAST PATH I263
J 2
(-5573 4800);
DISPLAY 0.872340 (-5573 4800);
PAINT GREEN (-5573 4800);
DISPLAY INVISIBLE (-5573 4800);
FORCEADD TAP..1
R 2
(-5575 4700);
FORCEPROP 3 LASTPIN (-5525 4700) SIG_NAME M_K_CPU0_SB_DQS_DP<2>
J 0
(-5515 4710);
DISPLAY 0.659574 (-5515 4710);
PAINT MONO (-5515 4710);
DISPLAY INVISIBLE (-5515 4710);
FORCEPROP 1 LASTPIN (-5525 4700) BN 2
J 2
(-5513 4708);
DISPLAY 0.489362 (-5513 4708);
PAINT GREEN (-5513 4708);
FORCEPROP 2 LAST CDS_LIB mstr_standard
J 2
(-5575 4700);
DISPLAY 0.723404 (-5575 4700);
PAINT MONO (-5575 4700);
DISPLAY INVISIBLE (-5575 4700);
FORCEPROP 1 LAST BODY_TYPE PLUMBING
J 2
(-5575 4750);
DISPLAY 0.872340 (-5575 4750);
PAINT GREEN (-5575 4750);
DISPLAY INVISIBLE (-5575 4750);
FORCEPROP 1 LAST HDL_TAP TRUE
J 2
(-5900 4575);
DISPLAY 0.872340 (-5900 4575);
DISPLAY INVISIBLE (-5900 4575);
FORCEPROP 1 LAST PATH I264
J 2
(-5573 4700);
DISPLAY 0.872340 (-5573 4700);
PAINT GREEN (-5573 4700);
DISPLAY INVISIBLE (-5573 4700);
FORCEADD TAP..1
R 2
(-5575 4600);
FORCEPROP 3 LASTPIN (-5525 4600) SIG_NAME M_K_CPU0_SB_DQS_DP<3>
J 0
(-5515 4610);
DISPLAY 0.659574 (-5515 4610);
PAINT MONO (-5515 4610);
DISPLAY INVISIBLE (-5515 4610);
FORCEPROP 1 LASTPIN (-5525 4600) BN 3
J 2
(-5513 4608);
DISPLAY 0.489362 (-5513 4608);
PAINT GREEN (-5513 4608);
FORCEPROP 2 LAST CDS_LIB mstr_standard
J 2
(-5575 4600);
DISPLAY 0.723404 (-5575 4600);
PAINT MONO (-5575 4600);
DISPLAY INVISIBLE (-5575 4600);
FORCEPROP 1 LAST BODY_TYPE PLUMBING
J 2
(-5575 4650);
DISPLAY 0.872340 (-5575 4650);
PAINT GREEN (-5575 4650);
DISPLAY INVISIBLE (-5575 4650);
FORCEPROP 1 LAST HDL_TAP TRUE
J 2
(-5900 4475);
DISPLAY 0.872340 (-5900 4475);
DISPLAY INVISIBLE (-5900 4475);
FORCEPROP 1 LAST PATH I265
J 2
(-5573 4600);
DISPLAY 0.872340 (-5573 4600);
PAINT GREEN (-5573 4600);
DISPLAY INVISIBLE (-5573 4600);
FORCEADD TAP..1
R 2
(-5575 4400);
FORCEPROP 3 LASTPIN (-5525 4400) SIG_NAME M_K_CPU0_SB_DQS_DP<5>
J 0
(-5515 4410);
DISPLAY 0.659574 (-5515 4410);
PAINT MONO (-5515 4410);
DISPLAY INVISIBLE (-5515 4410);
FORCEPROP 1 LASTPIN (-5525 4400) BN 5
J 2
(-5513 4408);
DISPLAY 0.489362 (-5513 4408);
PAINT GREEN (-5513 4408);
FORCEPROP 2 LAST CDS_LIB mstr_standard
J 2
(-5575 4400);
DISPLAY 0.723404 (-5575 4400);
PAINT MONO (-5575 4400);
DISPLAY INVISIBLE (-5575 4400);
FORCEPROP 1 LAST BODY_TYPE PLUMBING
J 2
(-5575 4450);
DISPLAY 0.872340 (-5575 4450);
PAINT GREEN (-5575 4450);
DISPLAY INVISIBLE (-5575 4450);
FORCEPROP 1 LAST HDL_TAP TRUE
J 2
(-5900 4275);
DISPLAY 0.872340 (-5900 4275);
DISPLAY INVISIBLE (-5900 4275);
FORCEPROP 1 LAST PATH I266
J 2
(-5573 4400);
DISPLAY 0.872340 (-5573 4400);
PAINT GREEN (-5573 4400);
DISPLAY INVISIBLE (-5573 4400);
FORCEADD TAP..1
R 2
(-5575 4500);
FORCEPROP 3 LASTPIN (-5525 4500) SIG_NAME M_K_CPU0_SB_DQS_DP<4>
J 0
(-5515 4510);
DISPLAY 0.659574 (-5515 4510);
PAINT MONO (-5515 4510);
DISPLAY INVISIBLE (-5515 4510);
FORCEPROP 1 LASTPIN (-5525 4500) BN 4
J 2
(-5513 4508);
DISPLAY 0.489362 (-5513 4508);
PAINT GREEN (-5513 4508);
FORCEPROP 2 LAST CDS_LIB mstr_standard
J 2
(-5575 4500);
DISPLAY 0.723404 (-5575 4500);
PAINT MONO (-5575 4500);
DISPLAY INVISIBLE (-5575 4500);
FORCEPROP 1 LAST BODY_TYPE PLUMBING
J 2
(-5575 4550);
DISPLAY 0.872340 (-5575 4550);
PAINT GREEN (-5575 4550);
DISPLAY INVISIBLE (-5575 4550);
FORCEPROP 1 LAST HDL_TAP TRUE
J 2
(-5900 4375);
DISPLAY 0.872340 (-5900 4375);
DISPLAY INVISIBLE (-5900 4375);
FORCEPROP 1 LAST PATH I267
J 2
(-5573 4500);
DISPLAY 0.872340 (-5573 4500);
PAINT GREEN (-5573 4500);
DISPLAY INVISIBLE (-5573 4500);
FORCEADD TAP..1
R 2
(-5575 4200);
FORCEPROP 3 LASTPIN (-5525 4200) SIG_NAME M_K_CPU0_SB_DQS_DP<7>
J 0
(-5515 4210);
DISPLAY 0.659574 (-5515 4210);
PAINT MONO (-5515 4210);
DISPLAY INVISIBLE (-5515 4210);
FORCEPROP 1 LASTPIN (-5525 4200) BN 7
J 2
(-5513 4208);
DISPLAY 0.489362 (-5513 4208);
PAINT GREEN (-5513 4208);
FORCEPROP 2 LAST CDS_LIB mstr_standard
J 2
(-5575 4200);
DISPLAY 0.723404 (-5575 4200);
PAINT MONO (-5575 4200);
DISPLAY INVISIBLE (-5575 4200);
FORCEPROP 1 LAST BODY_TYPE PLUMBING
J 2
(-5575 4250);
DISPLAY 0.872340 (-5575 4250);
PAINT GREEN (-5575 4250);
DISPLAY INVISIBLE (-5575 4250);
FORCEPROP 1 LAST HDL_TAP TRUE
J 2
(-5900 4075);
DISPLAY 0.872340 (-5900 4075);
DISPLAY INVISIBLE (-5900 4075);
FORCEPROP 1 LAST PATH I268
J 2
(-5573 4200);
DISPLAY 0.872340 (-5573 4200);
PAINT GREEN (-5573 4200);
DISPLAY INVISIBLE (-5573 4200);
FORCEADD TAP..1
R 2
(-5575 4300);
FORCEPROP 3 LASTPIN (-5525 4300) SIG_NAME M_K_CPU0_SB_DQS_DP<6>
J 0
(-5515 4310);
DISPLAY 0.659574 (-5515 4310);
PAINT MONO (-5515 4310);
DISPLAY INVISIBLE (-5515 4310);
FORCEPROP 1 LASTPIN (-5525 4300) BN 6
J 2
(-5513 4308);
DISPLAY 0.489362 (-5513 4308);
PAINT GREEN (-5513 4308);
FORCEPROP 2 LAST CDS_LIB mstr_standard
J 2
(-5575 4300);
DISPLAY 0.723404 (-5575 4300);
PAINT MONO (-5575 4300);
DISPLAY INVISIBLE (-5575 4300);
FORCEPROP 1 LAST BODY_TYPE PLUMBING
J 2
(-5575 4350);
DISPLAY 0.872340 (-5575 4350);
PAINT GREEN (-5575 4350);
DISPLAY INVISIBLE (-5575 4350);
FORCEPROP 1 LAST HDL_TAP TRUE
J 2
(-5900 4175);
DISPLAY 0.872340 (-5900 4175);
DISPLAY INVISIBLE (-5900 4175);
FORCEPROP 1 LAST PATH I269
J 2
(-5573 4300);
DISPLAY 0.872340 (-5573 4300);
PAINT GREEN (-5573 4300);
DISPLAY INVISIBLE (-5573 4300);
FORCEADD TAP..1
R 2
(-5575 4100);
FORCEPROP 3 LASTPIN (-5525 4100) SIG_NAME M_K_CPU0_SB_DQS_DP<8>
J 0
(-5515 4110);
DISPLAY 0.659574 (-5515 4110);
PAINT MONO (-5515 4110);
DISPLAY INVISIBLE (-5515 4110);
FORCEPROP 1 LASTPIN (-5525 4100) BN 8
J 2
(-5513 4108);
DISPLAY 0.489362 (-5513 4108);
PAINT GREEN (-5513 4108);
FORCEPROP 2 LAST CDS_LIB mstr_standard
J 2
(-5575 4100);
DISPLAY 0.723404 (-5575 4100);
PAINT MONO (-5575 4100);
DISPLAY INVISIBLE (-5575 4100);
FORCEPROP 1 LAST BODY_TYPE PLUMBING
J 2
(-5575 4150);
DISPLAY 0.872340 (-5575 4150);
PAINT GREEN (-5575 4150);
DISPLAY INVISIBLE (-5575 4150);
FORCEPROP 1 LAST HDL_TAP TRUE
J 2
(-5900 3975);
DISPLAY 0.872340 (-5900 3975);
DISPLAY INVISIBLE (-5900 3975);
FORCEPROP 1 LAST PATH I270
J 2
(-5573 4100);
DISPLAY 0.872340 (-5573 4100);
PAINT GREEN (-5573 4100);
DISPLAY INVISIBLE (-5573 4100);
FORCEADD TAP..1
R 2
(-5775 5100);
FORCEPROP 3 LASTPIN (-5725 5100) SIG_NAME M_K_CPU0_SA_DQS_DN<8>
J 0
(-5715 5110);
DISPLAY 0.659574 (-5715 5110);
PAINT MONO (-5715 5110);
DISPLAY INVISIBLE (-5715 5110);
FORCEPROP 1 LASTPIN (-5725 5100) BN 8
J 2
(-5713 5108);
DISPLAY 0.489362 (-5713 5108);
PAINT GREEN (-5713 5108);
FORCEPROP 2 LAST CDS_LIB mstr_standard
J 2
(-5775 5100);
DISPLAY 0.723404 (-5775 5100);
PAINT MONO (-5775 5100);
DISPLAY INVISIBLE (-5775 5100);
FORCEPROP 1 LAST BODY_TYPE PLUMBING
J 2
(-5775 5150);
DISPLAY 0.872340 (-5775 5150);
PAINT GREEN (-5775 5150);
DISPLAY INVISIBLE (-5775 5150);
FORCEPROP 1 LAST HDL_TAP TRUE
J 2
(-6100 4975);
DISPLAY 0.872340 (-6100 4975);
DISPLAY INVISIBLE (-6100 4975);
FORCEPROP 1 LAST PATH I271
J 2
(-5773 5100);
DISPLAY 0.872340 (-5773 5100);
PAINT GREEN (-5773 5100);
DISPLAY INVISIBLE (-5773 5100);
FORCEADD TAP..1
R 2
(-5775 5000);
FORCEPROP 3 LASTPIN (-5725 5000) SIG_NAME M_K_CPU0_SA_DQS_DN<9>
J 0
(-5715 5010);
DISPLAY 0.659574 (-5715 5010);
PAINT MONO (-5715 5010);
DISPLAY INVISIBLE (-5715 5010);
FORCEPROP 1 LASTPIN (-5725 5000) BN 9
J 2
(-5713 5008);
DISPLAY 0.489362 (-5713 5008);
PAINT GREEN (-5713 5008);
FORCEPROP 2 LAST CDS_LIB mstr_standard
J 2
(-5775 5000);
DISPLAY 0.723404 (-5775 5000);
PAINT MONO (-5775 5000);
DISPLAY INVISIBLE (-5775 5000);
FORCEPROP 1 LAST BODY_TYPE PLUMBING
J 2
(-5775 5050);
DISPLAY 0.872340 (-5775 5050);
PAINT GREEN (-5775 5050);
DISPLAY INVISIBLE (-5775 5050);
FORCEPROP 1 LAST HDL_TAP TRUE
J 2
(-6100 4875);
DISPLAY 0.872340 (-6100 4875);
DISPLAY INVISIBLE (-6100 4875);
FORCEPROP 1 LAST PATH I272
J 2
(-5773 5000);
DISPLAY 0.872340 (-5773 5000);
PAINT GREEN (-5773 5000);
DISPLAY INVISIBLE (-5773 5000);
FORCEADD TAP..1
R 2
(-5775 4850);
FORCEPROP 3 LASTPIN (-5725 4850) SIG_NAME M_K_CPU0_SB_DQS_DN<0>
J 0
(-5715 4860);
DISPLAY 0.659574 (-5715 4860);
PAINT MONO (-5715 4860);
DISPLAY INVISIBLE (-5715 4860);
FORCEPROP 1 LASTPIN (-5725 4850) BN 0
J 2
(-5713 4858);
DISPLAY 0.489362 (-5713 4858);
PAINT GREEN (-5713 4858);
FORCEPROP 2 LAST CDS_LIB mstr_standard
J 2
(-5775 4850);
DISPLAY 0.723404 (-5775 4850);
PAINT MONO (-5775 4850);
DISPLAY INVISIBLE (-5775 4850);
FORCEPROP 1 LAST BODY_TYPE PLUMBING
J 2
(-5775 4900);
DISPLAY 0.872340 (-5775 4900);
PAINT GREEN (-5775 4900);
DISPLAY INVISIBLE (-5775 4900);
FORCEPROP 1 LAST HDL_TAP TRUE
J 2
(-6100 4725);
DISPLAY 0.872340 (-6100 4725);
DISPLAY INVISIBLE (-6100 4725);
FORCEPROP 1 LAST PATH I273
J 2
(-5773 4850);
DISPLAY 0.872340 (-5773 4850);
PAINT GREEN (-5773 4850);
DISPLAY INVISIBLE (-5773 4850);
FORCEADD TAP..1
R 2
(-5775 4750);
FORCEPROP 3 LASTPIN (-5725 4750) SIG_NAME M_K_CPU0_SB_DQS_DN<1>
J 0
(-5715 4760);
DISPLAY 0.659574 (-5715 4760);
PAINT MONO (-5715 4760);
DISPLAY INVISIBLE (-5715 4760);
FORCEPROP 1 LASTPIN (-5725 4750) BN 1
J 2
(-5713 4758);
DISPLAY 0.489362 (-5713 4758);
PAINT GREEN (-5713 4758);
FORCEPROP 2 LAST CDS_LIB mstr_standard
J 2
(-5775 4750);
DISPLAY 0.723404 (-5775 4750);
PAINT MONO (-5775 4750);
DISPLAY INVISIBLE (-5775 4750);
FORCEPROP 1 LAST BODY_TYPE PLUMBING
J 2
(-5775 4800);
DISPLAY 0.872340 (-5775 4800);
PAINT GREEN (-5775 4800);
DISPLAY INVISIBLE (-5775 4800);
FORCEPROP 1 LAST HDL_TAP TRUE
J 2
(-6100 4625);
DISPLAY 0.872340 (-6100 4625);
DISPLAY INVISIBLE (-6100 4625);
FORCEPROP 1 LAST PATH I274
J 2
(-5773 4750);
DISPLAY 0.872340 (-5773 4750);
PAINT GREEN (-5773 4750);
DISPLAY INVISIBLE (-5773 4750);
FORCEADD TAP..1
R 2
(-5775 4650);
FORCEPROP 3 LASTPIN (-5725 4650) SIG_NAME M_K_CPU0_SB_DQS_DN<2>
J 0
(-5715 4660);
DISPLAY 0.659574 (-5715 4660);
PAINT MONO (-5715 4660);
DISPLAY INVISIBLE (-5715 4660);
FORCEPROP 1 LASTPIN (-5725 4650) BN 2
J 2
(-5713 4658);
DISPLAY 0.489362 (-5713 4658);
PAINT GREEN (-5713 4658);
FORCEPROP 2 LAST CDS_LIB mstr_standard
J 2
(-5775 4650);
DISPLAY 0.723404 (-5775 4650);
PAINT MONO (-5775 4650);
DISPLAY INVISIBLE (-5775 4650);
FORCEPROP 1 LAST BODY_TYPE PLUMBING
J 2
(-5775 4700);
DISPLAY 0.872340 (-5775 4700);
PAINT GREEN (-5775 4700);
DISPLAY INVISIBLE (-5775 4700);
FORCEPROP 1 LAST HDL_TAP TRUE
J 2
(-6100 4525);
DISPLAY 0.872340 (-6100 4525);
DISPLAY INVISIBLE (-6100 4525);
FORCEPROP 1 LAST PATH I275
J 2
(-5773 4650);
DISPLAY 0.872340 (-5773 4650);
PAINT GREEN (-5773 4650);
DISPLAY INVISIBLE (-5773 4650);
FORCEADD TAP..1
R 2
(-5775 4550);
FORCEPROP 3 LASTPIN (-5725 4550) SIG_NAME M_K_CPU0_SB_DQS_DN<3>
J 0
(-5715 4560);
DISPLAY 0.659574 (-5715 4560);
PAINT MONO (-5715 4560);
DISPLAY INVISIBLE (-5715 4560);
FORCEPROP 1 LASTPIN (-5725 4550) BN 3
J 2
(-5713 4558);
DISPLAY 0.489362 (-5713 4558);
PAINT GREEN (-5713 4558);
FORCEPROP 2 LAST CDS_LIB mstr_standard
J 2
(-5775 4550);
DISPLAY 0.723404 (-5775 4550);
PAINT MONO (-5775 4550);
DISPLAY INVISIBLE (-5775 4550);
FORCEPROP 1 LAST BODY_TYPE PLUMBING
J 2
(-5775 4600);
DISPLAY 0.872340 (-5775 4600);
PAINT GREEN (-5775 4600);
DISPLAY INVISIBLE (-5775 4600);
FORCEPROP 1 LAST HDL_TAP TRUE
J 2
(-6100 4425);
DISPLAY 0.872340 (-6100 4425);
DISPLAY INVISIBLE (-6100 4425);
FORCEPROP 1 LAST PATH I276
J 2
(-5773 4550);
DISPLAY 0.872340 (-5773 4550);
PAINT GREEN (-5773 4550);
DISPLAY INVISIBLE (-5773 4550);
FORCEADD TAP..1
R 2
(-5775 4450);
FORCEPROP 3 LASTPIN (-5725 4450) SIG_NAME M_K_CPU0_SB_DQS_DN<4>
J 0
(-5715 4460);
DISPLAY 0.659574 (-5715 4460);
PAINT MONO (-5715 4460);
DISPLAY INVISIBLE (-5715 4460);
FORCEPROP 1 LASTPIN (-5725 4450) BN 4
J 2
(-5713 4458);
DISPLAY 0.489362 (-5713 4458);
PAINT GREEN (-5713 4458);
FORCEPROP 2 LAST CDS_LIB mstr_standard
J 2
(-5775 4450);
DISPLAY 0.723404 (-5775 4450);
PAINT MONO (-5775 4450);
DISPLAY INVISIBLE (-5775 4450);
FORCEPROP 1 LAST BODY_TYPE PLUMBING
J 2
(-5775 4500);
DISPLAY 0.872340 (-5775 4500);
PAINT GREEN (-5775 4500);
DISPLAY INVISIBLE (-5775 4500);
FORCEPROP 1 LAST HDL_TAP TRUE
J 2
(-6100 4325);
DISPLAY 0.872340 (-6100 4325);
DISPLAY INVISIBLE (-6100 4325);
FORCEPROP 1 LAST PATH I277
J 2
(-5773 4450);
DISPLAY 0.872340 (-5773 4450);
PAINT GREEN (-5773 4450);
DISPLAY INVISIBLE (-5773 4450);
FORCEADD TAP..1
R 2
(-5775 4250);
FORCEPROP 3 LASTPIN (-5725 4250) SIG_NAME M_K_CPU0_SB_DQS_DN<6>
J 0
(-5715 4260);
DISPLAY 0.659574 (-5715 4260);
PAINT MONO (-5715 4260);
DISPLAY INVISIBLE (-5715 4260);
FORCEPROP 1 LASTPIN (-5725 4250) BN 6
J 2
(-5713 4258);
DISPLAY 0.489362 (-5713 4258);
PAINT GREEN (-5713 4258);
FORCEPROP 2 LAST CDS_LIB mstr_standard
J 2
(-5775 4250);
DISPLAY 0.723404 (-5775 4250);
PAINT MONO (-5775 4250);
DISPLAY INVISIBLE (-5775 4250);
FORCEPROP 1 LAST BODY_TYPE PLUMBING
J 2
(-5775 4300);
DISPLAY 0.872340 (-5775 4300);
PAINT GREEN (-5775 4300);
DISPLAY INVISIBLE (-5775 4300);
FORCEPROP 1 LAST HDL_TAP TRUE
J 2
(-6100 4125);
DISPLAY 0.872340 (-6100 4125);
DISPLAY INVISIBLE (-6100 4125);
FORCEPROP 1 LAST PATH I278
J 2
(-5773 4250);
DISPLAY 0.872340 (-5773 4250);
PAINT GREEN (-5773 4250);
DISPLAY INVISIBLE (-5773 4250);
FORCEADD TAP..1
R 2
(-5775 4350);
FORCEPROP 3 LASTPIN (-5725 4350) SIG_NAME M_K_CPU0_SB_DQS_DN<5>
J 0
(-5715 4360);
DISPLAY 0.659574 (-5715 4360);
PAINT MONO (-5715 4360);
DISPLAY INVISIBLE (-5715 4360);
FORCEPROP 1 LASTPIN (-5725 4350) BN 5
J 2
(-5713 4358);
DISPLAY 0.489362 (-5713 4358);
PAINT GREEN (-5713 4358);
FORCEPROP 2 LAST CDS_LIB mstr_standard
J 2
(-5775 4350);
DISPLAY 0.723404 (-5775 4350);
PAINT MONO (-5775 4350);
DISPLAY INVISIBLE (-5775 4350);
FORCEPROP 1 LAST BODY_TYPE PLUMBING
J 2
(-5775 4400);
DISPLAY 0.872340 (-5775 4400);
PAINT GREEN (-5775 4400);
DISPLAY INVISIBLE (-5775 4400);
FORCEPROP 1 LAST HDL_TAP TRUE
J 2
(-6100 4225);
DISPLAY 0.872340 (-6100 4225);
DISPLAY INVISIBLE (-6100 4225);
FORCEPROP 1 LAST PATH I279
J 2
(-5773 4350);
DISPLAY 0.872340 (-5773 4350);
PAINT GREEN (-5773 4350);
DISPLAY INVISIBLE (-5773 4350);
FORCEADD TAP..1
R 2
(-5775 4150);
FORCEPROP 3 LASTPIN (-5725 4150) SIG_NAME M_K_CPU0_SB_DQS_DN<7>
J 0
(-5715 4160);
DISPLAY 0.659574 (-5715 4160);
PAINT MONO (-5715 4160);
DISPLAY INVISIBLE (-5715 4160);
FORCEPROP 1 LASTPIN (-5725 4150) BN 7
J 2
(-5713 4158);
DISPLAY 0.489362 (-5713 4158);
PAINT GREEN (-5713 4158);
FORCEPROP 2 LAST CDS_LIB mstr_standard
J 2
(-5775 4150);
DISPLAY 0.723404 (-5775 4150);
PAINT MONO (-5775 4150);
DISPLAY INVISIBLE (-5775 4150);
FORCEPROP 1 LAST BODY_TYPE PLUMBING
J 2
(-5775 4200);
DISPLAY 0.872340 (-5775 4200);
PAINT GREEN (-5775 4200);
DISPLAY INVISIBLE (-5775 4200);
FORCEPROP 1 LAST HDL_TAP TRUE
J 2
(-6100 4025);
DISPLAY 0.872340 (-6100 4025);
DISPLAY INVISIBLE (-6100 4025);
FORCEPROP 1 LAST PATH I280
J 2
(-5773 4150);
DISPLAY 0.872340 (-5773 4150);
PAINT GREEN (-5773 4150);
DISPLAY INVISIBLE (-5773 4150);
FORCEADD OFFPAGE..3
R 2
(-6475 5925);
FORCEPROP 2 LAST $XR0 95 
J 0
(-6754 5925);
DISPLAY 0.638298 (-6754 5925);
PAINT MONO (-6754 5925);
FORCEPROP 2 LAST PATH I281
J 0
(-6775 5975);
DISPLAY 1.021277 (-6775 5975);
DISPLAY INVISIBLE (-6775 5975);
FORCEPROP 1 LAST COMMENT_BODY TRUE
J 2
(-6425 5825);
DISPLAY 0.872340 (-6425 5825);
PAINT GREEN (-6425 5825);
DISPLAY INVISIBLE (-6425 5825);
FORCEPROP 1 LAST OFFPAGE TRUE
J 2
(-6800 5800);
DISPLAY 0.872340 (-6800 5800);
PAINT GREEN (-6800 5800);
DISPLAY INVISIBLE (-6800 5800);
FORCEPROP 2 LAST CDS_LIB standard
J 0
(-6475 5925);
DISPLAY INVISIBLE (-6475 5925);
FORCEADD OFFPAGE..3
R 2
(-6475 5975);
FORCEPROP 2 LAST $XR0 95 
J 0
(-6754 5975);
DISPLAY 0.638298 (-6754 5975);
PAINT MONO (-6754 5975);
FORCEPROP 2 LAST PATH I282
J 0
(-6775 6025);
DISPLAY 1.021277 (-6775 6025);
DISPLAY INVISIBLE (-6775 6025);
FORCEPROP 1 LAST COMMENT_BODY TRUE
J 2
(-6425 5875);
DISPLAY 0.872340 (-6425 5875);
PAINT GREEN (-6425 5875);
DISPLAY INVISIBLE (-6425 5875);
FORCEPROP 1 LAST OFFPAGE TRUE
J 2
(-6800 5850);
DISPLAY 0.872340 (-6800 5850);
PAINT GREEN (-6800 5850);
DISPLAY INVISIBLE (-6800 5850);
FORCEPROP 2 LAST CDS_LIB standard
J 0
(-6475 5975);
DISPLAY INVISIBLE (-6475 5975);
FORCEADD OFFPAGE..3
R 2
(-6475 4925);
FORCEPROP 2 LAST $XR0 95 
J 0
(-6754 4925);
DISPLAY 0.638298 (-6754 4925);
PAINT MONO (-6754 4925);
FORCEPROP 2 LAST PATH I283
J 0
(-6775 4975);
DISPLAY 1.021277 (-6775 4975);
DISPLAY INVISIBLE (-6775 4975);
FORCEPROP 1 LAST COMMENT_BODY TRUE
J 2
(-6425 4825);
DISPLAY 0.872340 (-6425 4825);
PAINT GREEN (-6425 4825);
DISPLAY INVISIBLE (-6425 4825);
FORCEPROP 1 LAST OFFPAGE TRUE
J 2
(-6800 4800);
DISPLAY 0.872340 (-6800 4800);
PAINT GREEN (-6800 4800);
DISPLAY INVISIBLE (-6800 4800);
FORCEPROP 2 LAST CDS_LIB standard
J 0
(-6475 4925);
DISPLAY INVISIBLE (-6475 4925);
FORCEADD OFFPAGE..3
R 2
(-6475 4875);
FORCEPROP 2 LAST $XR0 95 
J 0
(-6754 4875);
DISPLAY 0.638298 (-6754 4875);
PAINT MONO (-6754 4875);
FORCEPROP 2 LAST PATH I284
J 0
(-6775 4925);
DISPLAY 1.021277 (-6775 4925);
DISPLAY INVISIBLE (-6775 4925);
FORCEPROP 1 LAST COMMENT_BODY TRUE
J 2
(-6425 4775);
DISPLAY 0.872340 (-6425 4775);
PAINT GREEN (-6425 4775);
DISPLAY INVISIBLE (-6425 4775);
FORCEPROP 1 LAST OFFPAGE TRUE
J 2
(-6800 4750);
DISPLAY 0.872340 (-6800 4750);
PAINT GREEN (-6800 4750);
DISPLAY INVISIBLE (-6800 4750);
FORCEPROP 2 LAST CDS_LIB standard
J 0
(-6475 4875);
DISPLAY INVISIBLE (-6475 4875);
FORCEADD TAP..1
R 2
(-5575 4000);
FORCEPROP 3 LASTPIN (-5525 4000) SIG_NAME M_K_CPU0_SB_DQS_DP<9>
J 0
(-5515 4010);
DISPLAY 0.659574 (-5515 4010);
PAINT MONO (-5515 4010);
DISPLAY INVISIBLE (-5515 4010);
FORCEPROP 1 LASTPIN (-5525 4000) BN 9
J 2
(-5513 4008);
DISPLAY 0.489362 (-5513 4008);
PAINT GREEN (-5513 4008);
FORCEPROP 2 LAST CDS_LIB mstr_standard
J 2
(-5575 4000);
DISPLAY 0.723404 (-5575 4000);
PAINT MONO (-5575 4000);
DISPLAY INVISIBLE (-5575 4000);
FORCEPROP 1 LAST BODY_TYPE PLUMBING
J 2
(-5575 4050);
DISPLAY 0.872340 (-5575 4050);
PAINT GREEN (-5575 4050);
DISPLAY INVISIBLE (-5575 4050);
FORCEPROP 1 LAST HDL_TAP TRUE
J 2
(-5900 3875);
DISPLAY 0.872340 (-5900 3875);
DISPLAY INVISIBLE (-5900 3875);
FORCEPROP 1 LAST PATH I285
J 2
(-5573 4000);
DISPLAY 0.872340 (-5573 4000);
PAINT GREEN (-5573 4000);
DISPLAY INVISIBLE (-5573 4000);
FORCEADD TAP..1
R 2
(-5775 4050);
FORCEPROP 3 LASTPIN (-5725 4050) SIG_NAME M_K_CPU0_SB_DQS_DN<8>
J 0
(-5715 4060);
DISPLAY 0.659574 (-5715 4060);
PAINT MONO (-5715 4060);
DISPLAY INVISIBLE (-5715 4060);
FORCEPROP 1 LASTPIN (-5725 4050) BN 8
J 2
(-5713 4058);
DISPLAY 0.489362 (-5713 4058);
PAINT GREEN (-5713 4058);
FORCEPROP 2 LAST CDS_LIB mstr_standard
J 2
(-5775 4050);
DISPLAY 0.723404 (-5775 4050);
PAINT MONO (-5775 4050);
DISPLAY INVISIBLE (-5775 4050);
FORCEPROP 1 LAST BODY_TYPE PLUMBING
J 2
(-5775 4100);
DISPLAY 0.872340 (-5775 4100);
PAINT GREEN (-5775 4100);
DISPLAY INVISIBLE (-5775 4100);
FORCEPROP 1 LAST HDL_TAP TRUE
J 2
(-6100 3925);
DISPLAY 0.872340 (-6100 3925);
DISPLAY INVISIBLE (-6100 3925);
FORCEPROP 1 LAST PATH I286
J 2
(-5773 4050);
DISPLAY 0.872340 (-5773 4050);
PAINT GREEN (-5773 4050);
DISPLAY INVISIBLE (-5773 4050);
FORCEADD TAP..1
R 2
(-5775 3950);
FORCEPROP 3 LASTPIN (-5725 3950) SIG_NAME M_K_CPU0_SB_DQS_DN<9>
J 0
(-5715 3960);
DISPLAY 0.659574 (-5715 3960);
PAINT MONO (-5715 3960);
DISPLAY INVISIBLE (-5715 3960);
FORCEPROP 1 LASTPIN (-5725 3950) BN 9
J 2
(-5713 3958);
DISPLAY 0.489362 (-5713 3958);
PAINT GREEN (-5713 3958);
FORCEPROP 2 LAST CDS_LIB mstr_standard
J 2
(-5775 3950);
DISPLAY 0.723404 (-5775 3950);
PAINT MONO (-5775 3950);
DISPLAY INVISIBLE (-5775 3950);
FORCEPROP 1 LAST BODY_TYPE PLUMBING
J 2
(-5775 4000);
DISPLAY 0.872340 (-5775 4000);
PAINT GREEN (-5775 4000);
DISPLAY INVISIBLE (-5775 4000);
FORCEPROP 1 LAST HDL_TAP TRUE
J 2
(-6100 3825);
DISPLAY 0.872340 (-6100 3825);
DISPLAY INVISIBLE (-6100 3825);
FORCEPROP 1 LAST PATH I287
J 2
(-5773 3950);
DISPLAY 0.872340 (-5773 3950);
PAINT GREEN (-5773 3950);
DISPLAY INVISIBLE (-5773 3950);
FORCEADD TAP..1
R 2
(-5775 3800);
FORCEPROP 3 LASTPIN (-5725 3800) SIG_NAME M_K_CPU0_SA_CA<0>
J 0
(-5715 3810);
DISPLAY 0.659574 (-5715 3810);
PAINT MONO (-5715 3810);
DISPLAY INVISIBLE (-5715 3810);
FORCEPROP 1 LASTPIN (-5725 3800) BN 0
J 2
(-5713 3808);
DISPLAY 0.489362 (-5713 3808);
PAINT GREEN (-5713 3808);
FORCEPROP 2 LAST CDS_LIB mstr_standard
J 0
(-5775 3800);
DISPLAY 0.723404 (-5775 3800);
PAINT MONO (-5775 3800);
DISPLAY INVISIBLE (-5775 3800);
FORCEPROP 1 LAST BODY_TYPE PLUMBING
J 2
(-5775 3850);
DISPLAY 0.872340 (-5775 3850);
PAINT GREEN (-5775 3850);
DISPLAY INVISIBLE (-5775 3850);
FORCEPROP 1 LAST HDL_TAP TRUE
J 2
(-6100 3675);
DISPLAY 0.872340 (-6100 3675);
DISPLAY INVISIBLE (-6100 3675);
FORCEPROP 1 LAST PATH I288
J 2
(-5773 3800);
DISPLAY 0.872340 (-5773 3800);
PAINT GREEN (-5773 3800);
DISPLAY INVISIBLE (-5773 3800);
FORCEADD TAP..1
R 2
(-5775 3750);
FORCEPROP 3 LASTPIN (-5725 3750) SIG_NAME M_K_CPU0_SA_CA<1>
J 0
(-5715 3760);
DISPLAY 0.659574 (-5715 3760);
PAINT MONO (-5715 3760);
DISPLAY INVISIBLE (-5715 3760);
FORCEPROP 1 LASTPIN (-5725 3750) BN 1
J 2
(-5713 3758);
DISPLAY 0.489362 (-5713 3758);
PAINT GREEN (-5713 3758);
FORCEPROP 2 LAST CDS_LIB mstr_standard
J 0
(-5775 3750);
DISPLAY 0.723404 (-5775 3750);
PAINT MONO (-5775 3750);
DISPLAY INVISIBLE (-5775 3750);
FORCEPROP 1 LAST BODY_TYPE PLUMBING
J 2
(-5775 3800);
DISPLAY 0.872340 (-5775 3800);
PAINT GREEN (-5775 3800);
DISPLAY INVISIBLE (-5775 3800);
FORCEPROP 1 LAST HDL_TAP TRUE
J 2
(-6100 3625);
DISPLAY 0.872340 (-6100 3625);
DISPLAY INVISIBLE (-6100 3625);
FORCEPROP 1 LAST PATH I289
J 2
(-5773 3750);
DISPLAY 0.872340 (-5773 3750);
PAINT GREEN (-5773 3750);
DISPLAY INVISIBLE (-5773 3750);
FORCEADD TAP..1
R 2
(-5775 3700);
FORCEPROP 3 LASTPIN (-5725 3700) SIG_NAME M_K_CPU0_SA_CA<2>
J 0
(-5715 3710);
DISPLAY 0.659574 (-5715 3710);
PAINT MONO (-5715 3710);
DISPLAY INVISIBLE (-5715 3710);
FORCEPROP 1 LASTPIN (-5725 3700) BN 2
J 2
(-5713 3708);
DISPLAY 0.489362 (-5713 3708);
PAINT GREEN (-5713 3708);
FORCEPROP 2 LAST CDS_LIB mstr_standard
J 0
(-5775 3700);
DISPLAY 0.723404 (-5775 3700);
PAINT MONO (-5775 3700);
DISPLAY INVISIBLE (-5775 3700);
FORCEPROP 1 LAST BODY_TYPE PLUMBING
J 2
(-5775 3750);
DISPLAY 0.872340 (-5775 3750);
PAINT GREEN (-5775 3750);
DISPLAY INVISIBLE (-5775 3750);
FORCEPROP 1 LAST HDL_TAP TRUE
J 2
(-6100 3575);
DISPLAY 0.872340 (-6100 3575);
DISPLAY INVISIBLE (-6100 3575);
FORCEPROP 1 LAST PATH I290
J 2
(-5773 3700);
DISPLAY 0.872340 (-5773 3700);
PAINT GREEN (-5773 3700);
DISPLAY INVISIBLE (-5773 3700);
FORCEADD TAP..1
R 2
(-5775 3650);
FORCEPROP 3 LASTPIN (-5725 3650) SIG_NAME M_K_CPU0_SA_CA<3>
J 0
(-5715 3660);
DISPLAY 0.659574 (-5715 3660);
PAINT MONO (-5715 3660);
DISPLAY INVISIBLE (-5715 3660);
FORCEPROP 1 LASTPIN (-5725 3650) BN 3
J 2
(-5713 3658);
DISPLAY 0.489362 (-5713 3658);
PAINT GREEN (-5713 3658);
FORCEPROP 2 LAST CDS_LIB mstr_standard
J 0
(-5775 3650);
DISPLAY 0.723404 (-5775 3650);
PAINT MONO (-5775 3650);
DISPLAY INVISIBLE (-5775 3650);
FORCEPROP 1 LAST BODY_TYPE PLUMBING
J 2
(-5775 3700);
DISPLAY 0.872340 (-5775 3700);
PAINT GREEN (-5775 3700);
DISPLAY INVISIBLE (-5775 3700);
FORCEPROP 1 LAST HDL_TAP TRUE
J 2
(-6100 3525);
DISPLAY 0.872340 (-6100 3525);
DISPLAY INVISIBLE (-6100 3525);
FORCEPROP 1 LAST PATH I291
J 2
(-5773 3650);
DISPLAY 0.872340 (-5773 3650);
PAINT GREEN (-5773 3650);
DISPLAY INVISIBLE (-5773 3650);
FORCEADD TAP..1
R 2
(-5775 3600);
FORCEPROP 3 LASTPIN (-5725 3600) SIG_NAME M_K_CPU0_SA_CA<4>
J 0
(-5715 3610);
DISPLAY 0.659574 (-5715 3610);
PAINT MONO (-5715 3610);
DISPLAY INVISIBLE (-5715 3610);
FORCEPROP 1 LASTPIN (-5725 3600) BN 4
J 2
(-5713 3608);
DISPLAY 0.489362 (-5713 3608);
PAINT GREEN (-5713 3608);
FORCEPROP 2 LAST CDS_LIB mstr_standard
J 0
(-5775 3600);
DISPLAY 0.723404 (-5775 3600);
PAINT MONO (-5775 3600);
DISPLAY INVISIBLE (-5775 3600);
FORCEPROP 1 LAST BODY_TYPE PLUMBING
J 2
(-5775 3650);
DISPLAY 0.872340 (-5775 3650);
PAINT GREEN (-5775 3650);
DISPLAY INVISIBLE (-5775 3650);
FORCEPROP 1 LAST HDL_TAP TRUE
J 2
(-6100 3475);
DISPLAY 0.872340 (-6100 3475);
DISPLAY INVISIBLE (-6100 3475);
FORCEPROP 1 LAST PATH I292
J 2
(-5773 3600);
DISPLAY 0.872340 (-5773 3600);
PAINT GREEN (-5773 3600);
DISPLAY INVISIBLE (-5773 3600);
FORCEADD TAP..1
R 2
(-5775 3500);
FORCEPROP 3 LASTPIN (-5725 3500) SIG_NAME M_K_CPU0_SA_CA<6>
J 0
(-5715 3510);
DISPLAY 0.659574 (-5715 3510);
PAINT MONO (-5715 3510);
DISPLAY INVISIBLE (-5715 3510);
FORCEPROP 1 LASTPIN (-5725 3500) BN 6
J 2
(-5713 3508);
DISPLAY 0.489362 (-5713 3508);
PAINT GREEN (-5713 3508);
FORCEPROP 2 LAST CDS_LIB mstr_standard
J 0
(-5775 3500);
DISPLAY 0.723404 (-5775 3500);
PAINT MONO (-5775 3500);
DISPLAY INVISIBLE (-5775 3500);
FORCEPROP 1 LAST BODY_TYPE PLUMBING
J 2
(-5775 3550);
DISPLAY 0.872340 (-5775 3550);
PAINT GREEN (-5775 3550);
DISPLAY INVISIBLE (-5775 3550);
FORCEPROP 1 LAST HDL_TAP TRUE
J 2
(-6100 3375);
DISPLAY 0.872340 (-6100 3375);
DISPLAY INVISIBLE (-6100 3375);
FORCEPROP 1 LAST PATH I293
J 2
(-5773 3500);
DISPLAY 0.872340 (-5773 3500);
PAINT GREEN (-5773 3500);
DISPLAY INVISIBLE (-5773 3500);
FORCEADD TAP..1
R 2
(-5775 3550);
FORCEPROP 3 LASTPIN (-5725 3550) SIG_NAME M_K_CPU0_SA_CA<5>
J 0
(-5715 3560);
DISPLAY 0.659574 (-5715 3560);
PAINT MONO (-5715 3560);
DISPLAY INVISIBLE (-5715 3560);
FORCEPROP 1 LASTPIN (-5725 3550) BN 5
J 2
(-5713 3558);
DISPLAY 0.489362 (-5713 3558);
PAINT GREEN (-5713 3558);
FORCEPROP 2 LAST CDS_LIB mstr_standard
J 0
(-5775 3550);
DISPLAY 0.723404 (-5775 3550);
PAINT MONO (-5775 3550);
DISPLAY INVISIBLE (-5775 3550);
FORCEPROP 1 LAST BODY_TYPE PLUMBING
J 2
(-5775 3600);
DISPLAY 0.872340 (-5775 3600);
PAINT GREEN (-5775 3600);
DISPLAY INVISIBLE (-5775 3600);
FORCEPROP 1 LAST HDL_TAP TRUE
J 2
(-6100 3425);
DISPLAY 0.872340 (-6100 3425);
DISPLAY INVISIBLE (-6100 3425);
FORCEPROP 1 LAST PATH I294
J 2
(-5773 3550);
DISPLAY 0.872340 (-5773 3550);
PAINT GREEN (-5773 3550);
DISPLAY INVISIBLE (-5773 3550);
FORCEADD TAP..1
R 2
(-5775 3400);
FORCEPROP 3 LASTPIN (-5725 3400) SIG_NAME M_K_CPU0_SB_CA<0>
J 0
(-5715 3410);
DISPLAY 0.659574 (-5715 3410);
PAINT MONO (-5715 3410);
DISPLAY INVISIBLE (-5715 3410);
FORCEPROP 1 LASTPIN (-5725 3400) BN 0
J 2
(-5713 3408);
DISPLAY 0.489362 (-5713 3408);
PAINT GREEN (-5713 3408);
FORCEPROP 2 LAST CDS_LIB mstr_standard
J 0
(-5775 3400);
DISPLAY 0.723404 (-5775 3400);
PAINT MONO (-5775 3400);
DISPLAY INVISIBLE (-5775 3400);
FORCEPROP 1 LAST BODY_TYPE PLUMBING
J 2
(-5775 3450);
DISPLAY 0.872340 (-5775 3450);
PAINT GREEN (-5775 3450);
DISPLAY INVISIBLE (-5775 3450);
FORCEPROP 1 LAST HDL_TAP TRUE
J 2
(-6100 3275);
DISPLAY 0.872340 (-6100 3275);
DISPLAY INVISIBLE (-6100 3275);
FORCEPROP 1 LAST PATH I295
J 2
(-5773 3400);
DISPLAY 0.872340 (-5773 3400);
PAINT GREEN (-5773 3400);
DISPLAY INVISIBLE (-5773 3400);
FORCEADD TAP..1
R 2
(-5775 3350);
FORCEPROP 3 LASTPIN (-5725 3350) SIG_NAME M_K_CPU0_SB_CA<1>
J 0
(-5715 3360);
DISPLAY 0.659574 (-5715 3360);
PAINT MONO (-5715 3360);
DISPLAY INVISIBLE (-5715 3360);
FORCEPROP 1 LASTPIN (-5725 3350) BN 1
J 2
(-5713 3358);
DISPLAY 0.489362 (-5713 3358);
PAINT GREEN (-5713 3358);
FORCEPROP 2 LAST CDS_LIB mstr_standard
J 0
(-5775 3350);
DISPLAY 0.723404 (-5775 3350);
PAINT MONO (-5775 3350);
DISPLAY INVISIBLE (-5775 3350);
FORCEPROP 1 LAST BODY_TYPE PLUMBING
J 2
(-5775 3400);
DISPLAY 0.872340 (-5775 3400);
PAINT GREEN (-5775 3400);
DISPLAY INVISIBLE (-5775 3400);
FORCEPROP 1 LAST HDL_TAP TRUE
J 2
(-6100 3225);
DISPLAY 0.872340 (-6100 3225);
DISPLAY INVISIBLE (-6100 3225);
FORCEPROP 1 LAST PATH I296
J 2
(-5773 3350);
DISPLAY 0.872340 (-5773 3350);
PAINT GREEN (-5773 3350);
DISPLAY INVISIBLE (-5773 3350);
FORCEADD TAP..1
R 2
(-5775 3300);
FORCEPROP 3 LASTPIN (-5725 3300) SIG_NAME M_K_CPU0_SB_CA<2>
J 0
(-5715 3310);
DISPLAY 0.659574 (-5715 3310);
PAINT MONO (-5715 3310);
DISPLAY INVISIBLE (-5715 3310);
FORCEPROP 1 LASTPIN (-5725 3300) BN 2
J 2
(-5713 3308);
DISPLAY 0.489362 (-5713 3308);
PAINT GREEN (-5713 3308);
FORCEPROP 2 LAST CDS_LIB mstr_standard
J 0
(-5775 3300);
DISPLAY 0.723404 (-5775 3300);
PAINT MONO (-5775 3300);
DISPLAY INVISIBLE (-5775 3300);
FORCEPROP 1 LAST BODY_TYPE PLUMBING
J 2
(-5775 3350);
DISPLAY 0.872340 (-5775 3350);
PAINT GREEN (-5775 3350);
DISPLAY INVISIBLE (-5775 3350);
FORCEPROP 1 LAST HDL_TAP TRUE
J 2
(-6100 3175);
DISPLAY 0.872340 (-6100 3175);
DISPLAY INVISIBLE (-6100 3175);
FORCEPROP 1 LAST PATH I297
J 2
(-5773 3300);
DISPLAY 0.872340 (-5773 3300);
PAINT GREEN (-5773 3300);
DISPLAY INVISIBLE (-5773 3300);
FORCEADD TAP..1
R 2
(-5775 3250);
FORCEPROP 3 LASTPIN (-5725 3250) SIG_NAME M_K_CPU0_SB_CA<3>
J 0
(-5715 3260);
DISPLAY 0.659574 (-5715 3260);
PAINT MONO (-5715 3260);
DISPLAY INVISIBLE (-5715 3260);
FORCEPROP 1 LASTPIN (-5725 3250) BN 3
J 2
(-5713 3258);
DISPLAY 0.489362 (-5713 3258);
PAINT GREEN (-5713 3258);
FORCEPROP 2 LAST CDS_LIB mstr_standard
J 0
(-5775 3250);
DISPLAY 0.723404 (-5775 3250);
PAINT MONO (-5775 3250);
DISPLAY INVISIBLE (-5775 3250);
FORCEPROP 1 LAST BODY_TYPE PLUMBING
J 2
(-5775 3300);
DISPLAY 0.872340 (-5775 3300);
PAINT GREEN (-5775 3300);
DISPLAY INVISIBLE (-5775 3300);
FORCEPROP 1 LAST HDL_TAP TRUE
J 2
(-6100 3125);
DISPLAY 0.872340 (-6100 3125);
DISPLAY INVISIBLE (-6100 3125);
FORCEPROP 1 LAST PATH I298
J 2
(-5773 3250);
DISPLAY 0.872340 (-5773 3250);
PAINT GREEN (-5773 3250);
DISPLAY INVISIBLE (-5773 3250);
FORCEADD TAP..1
R 2
(-5775 3200);
FORCEPROP 3 LASTPIN (-5725 3200) SIG_NAME M_K_CPU0_SB_CA<4>
J 0
(-5715 3210);
DISPLAY 0.659574 (-5715 3210);
PAINT MONO (-5715 3210);
DISPLAY INVISIBLE (-5715 3210);
FORCEPROP 1 LASTPIN (-5725 3200) BN 4
J 2
(-5713 3208);
DISPLAY 0.489362 (-5713 3208);
PAINT GREEN (-5713 3208);
FORCEPROP 2 LAST CDS_LIB mstr_standard
J 0
(-5775 3200);
DISPLAY 0.723404 (-5775 3200);
PAINT MONO (-5775 3200);
DISPLAY INVISIBLE (-5775 3200);
FORCEPROP 1 LAST BODY_TYPE PLUMBING
J 2
(-5775 3250);
DISPLAY 0.872340 (-5775 3250);
PAINT GREEN (-5775 3250);
DISPLAY INVISIBLE (-5775 3250);
FORCEPROP 1 LAST HDL_TAP TRUE
J 2
(-6100 3075);
DISPLAY 0.872340 (-6100 3075);
DISPLAY INVISIBLE (-6100 3075);
FORCEPROP 1 LAST PATH I299
J 2
(-5773 3200);
DISPLAY 0.872340 (-5773 3200);
PAINT GREEN (-5773 3200);
DISPLAY INVISIBLE (-5773 3200);
FORCEADD TAP..1
R 2
(-5775 3100);
FORCEPROP 3 LASTPIN (-5725 3100) SIG_NAME M_K_CPU0_SB_CA<6>
J 0
(-5715 3110);
DISPLAY 0.659574 (-5715 3110);
PAINT MONO (-5715 3110);
DISPLAY INVISIBLE (-5715 3110);
FORCEPROP 1 LASTPIN (-5725 3100) BN 6
J 2
(-5713 3108);
DISPLAY 0.489362 (-5713 3108);
PAINT GREEN (-5713 3108);
FORCEPROP 2 LAST CDS_LIB mstr_standard
J 0
(-5775 3100);
DISPLAY 0.723404 (-5775 3100);
PAINT MONO (-5775 3100);
DISPLAY INVISIBLE (-5775 3100);
FORCEPROP 1 LAST BODY_TYPE PLUMBING
J 2
(-5775 3150);
DISPLAY 0.872340 (-5775 3150);
PAINT GREEN (-5775 3150);
DISPLAY INVISIBLE (-5775 3150);
FORCEPROP 1 LAST HDL_TAP TRUE
J 2
(-6100 2975);
DISPLAY 0.872340 (-6100 2975);
DISPLAY INVISIBLE (-6100 2975);
FORCEPROP 1 LAST PATH I300
J 2
(-5773 3100);
DISPLAY 0.872340 (-5773 3100);
PAINT GREEN (-5773 3100);
DISPLAY INVISIBLE (-5773 3100);
FORCEADD TAP..1
R 2
(-5775 3150);
FORCEPROP 3 LASTPIN (-5725 3150) SIG_NAME M_K_CPU0_SB_CA<5>
J 0
(-5715 3160);
DISPLAY 0.659574 (-5715 3160);
PAINT MONO (-5715 3160);
DISPLAY INVISIBLE (-5715 3160);
FORCEPROP 1 LASTPIN (-5725 3150) BN 5
J 2
(-5713 3158);
DISPLAY 0.489362 (-5713 3158);
PAINT GREEN (-5713 3158);
FORCEPROP 2 LAST CDS_LIB mstr_standard
J 0
(-5775 3150);
DISPLAY 0.723404 (-5775 3150);
PAINT MONO (-5775 3150);
DISPLAY INVISIBLE (-5775 3150);
FORCEPROP 1 LAST BODY_TYPE PLUMBING
J 2
(-5775 3200);
DISPLAY 0.872340 (-5775 3200);
PAINT GREEN (-5775 3200);
DISPLAY INVISIBLE (-5775 3200);
FORCEPROP 1 LAST HDL_TAP TRUE
J 2
(-6100 3025);
DISPLAY 0.872340 (-6100 3025);
DISPLAY INVISIBLE (-6100 3025);
FORCEPROP 1 LAST PATH I301
J 2
(-5773 3150);
DISPLAY 0.872340 (-5773 3150);
PAINT GREEN (-5773 3150);
DISPLAY INVISIBLE (-5773 3150);
FORCEADD OFFPAGE..2
R 2
(-6375 3825);
FORCEPROP 2 LAST $XR0 95 
J 0
(-6629 3825);
DISPLAY 0.638298 (-6629 3825);
PAINT MONO (-6629 3825);
FORCEPROP 2 LAST PATH I302
J 0
(-6650 3875);
DISPLAY 1.021277 (-6650 3875);
DISPLAY INVISIBLE (-6650 3875);
FORCEPROP 1 LAST COMMENT_BODY TRUE
J 2
(-6330 3730);
DISPLAY 0.872340 (-6330 3730);
PAINT GREEN (-6330 3730);
DISPLAY INVISIBLE (-6330 3730);
FORCEPROP 1 LAST OFFPAGE TRUE
J 2
(-6700 3700);
DISPLAY 0.872340 (-6700 3700);
PAINT GREEN (-6700 3700);
DISPLAY INVISIBLE (-6700 3700);
FORCEPROP 2 LAST CDS_LIB standard
J 0
(-6375 3825);
DISPLAY INVISIBLE (-6375 3825);
FORCEADD OFFPAGE..2
R 2
(-6375 3425);
FORCEPROP 2 LAST $XR0 95 
J 0
(-6629 3425);
DISPLAY 0.638298 (-6629 3425);
PAINT MONO (-6629 3425);
FORCEPROP 2 LAST PATH I303
J 0
(-6650 3475);
DISPLAY 1.021277 (-6650 3475);
DISPLAY INVISIBLE (-6650 3475);
FORCEPROP 1 LAST COMMENT_BODY TRUE
J 2
(-6330 3330);
DISPLAY 0.872340 (-6330 3330);
PAINT GREEN (-6330 3330);
DISPLAY INVISIBLE (-6330 3330);
FORCEPROP 1 LAST OFFPAGE TRUE
J 2
(-6700 3300);
DISPLAY 0.872340 (-6700 3300);
PAINT GREEN (-6700 3300);
DISPLAY INVISIBLE (-6700 3300);
FORCEPROP 2 LAST CDS_LIB standard
J 0
(-6375 3425);
DISPLAY INVISIBLE (-6375 3425);
FORCEADD OFFPAGE..2
R 2
(-6375 2950);
FORCEPROP 2 LAST $XR0 95 
J 0
(-6629 2950);
DISPLAY 0.638298 (-6629 2950);
PAINT MONO (-6629 2950);
FORCEPROP 2 LAST PATH I304
J 0
(-6650 3000);
DISPLAY 1.021277 (-6650 3000);
DISPLAY INVISIBLE (-6650 3000);
FORCEPROP 1 LAST COMMENT_BODY TRUE
J 2
(-6330 2855);
DISPLAY 0.872340 (-6330 2855);
PAINT GREEN (-6330 2855);
DISPLAY INVISIBLE (-6330 2855);
FORCEPROP 1 LAST OFFPAGE TRUE
J 2
(-6700 2825);
DISPLAY 0.872340 (-6700 2825);
PAINT GREEN (-6700 2825);
DISPLAY INVISIBLE (-6700 2825);
FORCEPROP 2 LAST CDS_LIB standard
J 0
(-6375 2950);
DISPLAY INVISIBLE (-6375 2950);
FORCEADD OFFPAGE..2
R 2
(-6375 2900);
FORCEPROP 2 LAST $XR0 95 
J 0
(-6629 2900);
DISPLAY 0.638298 (-6629 2900);
PAINT MONO (-6629 2900);
FORCEPROP 2 LAST PATH I305
J 0
(-6650 2950);
DISPLAY 1.021277 (-6650 2950);
DISPLAY INVISIBLE (-6650 2950);
FORCEPROP 1 LAST COMMENT_BODY TRUE
J 2
(-6330 2805);
DISPLAY 0.872340 (-6330 2805);
PAINT GREEN (-6330 2805);
DISPLAY INVISIBLE (-6330 2805);
FORCEPROP 1 LAST OFFPAGE TRUE
J 2
(-6700 2775);
DISPLAY 0.872340 (-6700 2775);
PAINT GREEN (-6700 2775);
DISPLAY INVISIBLE (-6700 2775);
FORCEPROP 2 LAST CDS_LIB standard
J 0
(-6375 2900);
DISPLAY INVISIBLE (-6375 2900);
FORCEADD OFFPAGE..2
R 2
(-6375 2800);
FORCEPROP 2 LAST $XR0 95 
J 0
(-6629 2800);
DISPLAY 0.638298 (-6629 2800);
PAINT MONO (-6629 2800);
FORCEPROP 2 LAST PATH I306
J 0
(-6650 2850);
DISPLAY 1.021277 (-6650 2850);
DISPLAY INVISIBLE (-6650 2850);
FORCEPROP 1 LAST COMMENT_BODY TRUE
J 2
(-6330 2705);
DISPLAY 0.872340 (-6330 2705);
PAINT GREEN (-6330 2705);
DISPLAY INVISIBLE (-6330 2705);
FORCEPROP 1 LAST OFFPAGE TRUE
J 2
(-6700 2675);
DISPLAY 0.872340 (-6700 2675);
PAINT GREEN (-6700 2675);
DISPLAY INVISIBLE (-6700 2675);
FORCEPROP 2 LAST CDS_LIB standard
J 0
(-6375 2800);
DISPLAY INVISIBLE (-6375 2800);
FORCEADD OFFPAGE..1
(-6375 2650);
FORCEPROP 2 LAST $XR0 95 
J 0
(-6596 2650);
DISPLAY 0.638298 (-6596 2650);
PAINT MONO (-6596 2650);
FORCEPROP 2 LAST PATH I307
J 0
(-6625 2700);
DISPLAY 1.021277 (-6625 2700);
DISPLAY INVISIBLE (-6625 2700);
FORCEPROP 1 LAST COMMENT_BODY TRUE
J 0
(-6250 2550);
DISPLAY 0.872340 (-6250 2550);
PAINT GREEN (-6250 2550);
DISPLAY INVISIBLE (-6250 2550);
FORCEPROP 1 LAST OFFPAGE TRUE
J 0
(-6050 2525);
DISPLAY 0.872340 (-6050 2525);
PAINT GREEN (-6050 2525);
DISPLAY INVISIBLE (-6050 2525);
FORCEPROP 2 LAST CDS_LIB standard
J 0
(-6375 2650);
DISPLAY INVISIBLE (-6375 2650);
FORCEADD OFFPAGE..2
R 2
(-6375 2750);
FORCEPROP 2 LAST $XR0 95 
J 0
(-6629 2750);
DISPLAY 0.638298 (-6629 2750);
PAINT MONO (-6629 2750);
FORCEPROP 2 LAST PATH I308
J 0
(-6650 2800);
DISPLAY 1.021277 (-6650 2800);
DISPLAY INVISIBLE (-6650 2800);
FORCEPROP 1 LAST COMMENT_BODY TRUE
J 2
(-6330 2655);
DISPLAY 0.872340 (-6330 2655);
PAINT GREEN (-6330 2655);
DISPLAY INVISIBLE (-6330 2655);
FORCEPROP 1 LAST OFFPAGE TRUE
J 2
(-6700 2625);
DISPLAY 0.872340 (-6700 2625);
PAINT GREEN (-6700 2625);
DISPLAY INVISIBLE (-6700 2625);
FORCEPROP 2 LAST CDS_LIB standard
J 0
(-6375 2750);
DISPLAY INVISIBLE (-6375 2750);
FORCEADD OFFPAGE..5
(-6375 2550);
FORCEPROP 2 LAST $XR0 95 
J 0
(-6629 2550);
DISPLAY 0.638298 (-6629 2550);
PAINT MONO (-6629 2550);
FORCEPROP 2 LAST PATH I309
J 0
(-6650 2600);
DISPLAY 1.021277 (-6650 2600);
DISPLAY INVISIBLE (-6650 2600);
FORCEPROP 1 LAST COMMENT_BODY TRUE
J 0
(-6275 2475);
DISPLAY 0.872340 (-6275 2475);
PAINT GREEN (-6275 2475);
DISPLAY INVISIBLE (-6275 2475);
FORCEPROP 1 LAST OFFPAGE TRUE
J 0
(-6050 2425);
DISPLAY 0.872340 (-6050 2425);
PAINT GREEN (-6050 2425);
DISPLAY INVISIBLE (-6050 2425);
FORCEPROP 2 LAST CDS_LIB mstr_standard
J 0
(-6375 2550);
DISPLAY INVISIBLE (-6375 2550);
FORCEADD OFFPAGE..2
R 2
(-6375 2450);
FORCEPROP 2 LAST $XR0 95 
J 0
(-6629 2450);
DISPLAY 0.638298 (-6629 2450);
PAINT MONO (-6629 2450);
FORCEPROP 2 LAST PATH I310
J 0
(-6650 2500);
DISPLAY 1.021277 (-6650 2500);
DISPLAY INVISIBLE (-6650 2500);
FORCEPROP 1 LAST COMMENT_BODY TRUE
J 2
(-6330 2355);
DISPLAY 0.872340 (-6330 2355);
PAINT GREEN (-6330 2355);
DISPLAY INVISIBLE (-6330 2355);
FORCEPROP 1 LAST OFFPAGE TRUE
J 2
(-6700 2325);
DISPLAY 0.872340 (-6700 2325);
PAINT GREEN (-6700 2325);
DISPLAY INVISIBLE (-6700 2325);
FORCEPROP 2 LAST CDS_LIB standard
J 0
(-6375 2450);
DISPLAY INVISIBLE (-6375 2450);
FORCEADD OFFPAGE..2
R 2
(-6375 2400);
FORCEPROP 2 LAST $XR0 95 
J 0
(-6629 2400);
DISPLAY 0.638298 (-6629 2400);
PAINT MONO (-6629 2400);
FORCEPROP 2 LAST PATH I311
J 0
(-6650 2450);
DISPLAY 1.021277 (-6650 2450);
DISPLAY INVISIBLE (-6650 2450);
FORCEPROP 1 LAST COMMENT_BODY TRUE
J 2
(-6330 2305);
DISPLAY 0.872340 (-6330 2305);
PAINT GREEN (-6330 2305);
DISPLAY INVISIBLE (-6330 2305);
FORCEPROP 1 LAST OFFPAGE TRUE
J 2
(-6700 2275);
DISPLAY 0.872340 (-6700 2275);
PAINT GREEN (-6700 2275);
DISPLAY INVISIBLE (-6700 2275);
FORCEPROP 2 LAST CDS_LIB standard
J 0
(-6375 2400);
DISPLAY INVISIBLE (-6375 2400);
FORCEADD OFFPAGE..1
(-6375 2300);
FORCEPROP 2 LAST $XR0 95 
J 0
(-6596 2300);
DISPLAY 0.638298 (-6596 2300);
PAINT MONO (-6596 2300);
FORCEPROP 2 LAST PATH I312
J 0
(-6625 2350);
DISPLAY 1.021277 (-6625 2350);
DISPLAY INVISIBLE (-6625 2350);
FORCEPROP 1 LAST COMMENT_BODY TRUE
J 0
(-6250 2200);
DISPLAY 0.872340 (-6250 2200);
PAINT GREEN (-6250 2200);
DISPLAY INVISIBLE (-6250 2200);
FORCEPROP 1 LAST OFFPAGE TRUE
J 0
(-6050 2175);
DISPLAY 0.872340 (-6050 2175);
PAINT GREEN (-6050 2175);
DISPLAY INVISIBLE (-6050 2175);
FORCEPROP 2 LAST CDS_LIB standard
J 0
(-6375 2300);
DISPLAY INVISIBLE (-6375 2300);
FORCEADD OFFPAGE..5
(-6375 2200);
FORCEPROP 2 LAST $XR0 95 
J 0
(-6629 2200);
DISPLAY 0.638298 (-6629 2200);
PAINT MONO (-6629 2200);
FORCEPROP 2 LAST PATH I313
J 0
(-6650 2250);
DISPLAY 1.021277 (-6650 2250);
DISPLAY INVISIBLE (-6650 2250);
FORCEPROP 1 LAST COMMENT_BODY TRUE
J 0
(-6275 2125);
DISPLAY 0.872340 (-6275 2125);
PAINT GREEN (-6275 2125);
DISPLAY INVISIBLE (-6275 2125);
FORCEPROP 1 LAST OFFPAGE TRUE
J 0
(-6050 2075);
DISPLAY 0.872340 (-6050 2075);
PAINT GREEN (-6050 2075);
DISPLAY INVISIBLE (-6050 2075);
FORCEPROP 2 LAST CDS_LIB standard
J 0
(-6375 2200);
DISPLAY INVISIBLE (-6375 2200);
FORCEADD Q_RES..1
(-6700 2100);
FORCEPROP 1 LAST LOCATION R385
J 0
(-7025 2100);
DISPLAY 0.489362 (-7025 2100);
PAINT SKYBLUE (-7025 2100);
FORCEPROP 0 LAST $SEC 1
J 0
(-6875 2150);
DISPLAY 0.680851 (-6875 2150);
PAINT MONO (-6875 2150);
DISPLAY INVISIBLE (-6875 2150);
FORCEPROP 0 LAST CDS_SEC 1
J 0
(-6875 2150);
DISPLAY 1.021277 (-6875 2150);
DISPLAY INVISIBLE (-6875 2150);
FORCEPROP 1 LASTPIN (-6800 2100) $PN 1
J 0
(-6788 2112);
DISPLAY 0.489362 (-6788 2112);
PAINT MONO (-6788 2112);
FORCEPROP 1 LASTPIN (-6600 2100) $PN 2
J 0
(-6638 2112);
DISPLAY 0.489362 (-6638 2112);
PAINT MONO (-6638 2112);
FORCEPROP 1 LAST TOLERANCE 1%
J 0
(-6425 2100);
DISPLAY 0.489362 (-6425 2100);
PAINT SKYBLUE (-6425 2100);
FORCEPROP 1 LAST VALUE 15   
J 2
(-6375 2100);
DISPLAY 0.489362 (-6375 2100);
PAINT SKYBLUE (-6375 2100);
FORCEPROP 1 LAST PART_NUMBER CS01502FB11
J 0
(-6575 2075);
DISPLAY 0.489362 (-6575 2075);
PAINT SKYBLUE (-6575 2075);
FORCEPROP 1 LAST PACK_TYPE 0402LF
J 0
(-7025 2075);
DISPLAY 0.489362 (-7025 2075);
PAINT SKYBLUE (-7025 2075);
FORCEPROP 2 LAST CDS_LIB pure_quanta
J 0
(-6700 2100);
DISPLAY INVISIBLE (-6700 2100);
FORCEPROP 1 LAST PATH I314
J 0
(-6750 2250);
DISPLAY 0.978723 (-6750 2250);
PAINT WHITE (-6750 2250);
DISPLAY INVISIBLE (-6750 2250);
FORCEPROP 1 LAST WATTAGE 1/16W
J 2
(-6475 2225);
DISPLAY 0.638298 (-6475 2225);
PAINT SKYBLUE (-6475 2225);
DISPLAY INVISIBLE (-6475 2225);
FORCEPROP 1 LAST MATERIAL CHIP
J 0
(-6825 2225);
DISPLAY 0.638298 (-6825 2225);
PAINT SKYBLUE (-6825 2225);
DISPLAY INVISIBLE (-6825 2225);
FORCEADD OFFPAGE..1
(-7575 2100);
FORCEPROP 2 LAST $XR0 95 
J 0
(-7826 2100);
DISPLAY 0.638298 (-7826 2100);
PAINT MONO (-7826 2100);
FORCEPROP 2 LAST PATH I315
J 0
(-7850 2150);
DISPLAY 1.021277 (-7850 2150);
DISPLAY INVISIBLE (-7850 2150);
FORCEPROP 1 LAST COMMENT_BODY TRUE
J 0
(-7450 2000);
DISPLAY 0.872340 (-7450 2000);
PAINT GREEN (-7450 2000);
DISPLAY INVISIBLE (-7450 2000);
FORCEPROP 1 LAST OFFPAGE TRUE
J 0
(-7250 1975);
DISPLAY 0.872340 (-7250 1975);
PAINT GREEN (-7250 1975);
DISPLAY INVISIBLE (-7250 1975);
FORCEPROP 2 LAST CDS_LIB mstr_standard
J 0
(-7575 2100);
DISPLAY INVISIBLE (-7575 2100);
FORCEADD OFFPAGE..5
(-6375 2000);
FORCEPROP 2 LAST $XR0 95 
J 0
(-6629 2000);
DISPLAY 0.638298 (-6629 2000);
PAINT MONO (-6629 2000);
FORCEPROP 2 LAST PATH I316
J 0
(-6650 2050);
DISPLAY 1.021277 (-6650 2050);
DISPLAY INVISIBLE (-6650 2050);
FORCEPROP 1 LAST COMMENT_BODY TRUE
J 0
(-6275 1925);
DISPLAY 0.872340 (-6275 1925);
PAINT GREEN (-6275 1925);
DISPLAY INVISIBLE (-6275 1925);
FORCEPROP 1 LAST OFFPAGE TRUE
J 0
(-6050 1875);
DISPLAY 0.872340 (-6050 1875);
PAINT GREEN (-6050 1875);
DISPLAY INVISIBLE (-6050 1875);
FORCEPROP 2 LAST CDS_LIB standard
J 0
(-6375 2000);
DISPLAY INVISIBLE (-6375 2000);
FORCEADD CAD_NOTE..1
(-7525 2400);
FORCEPROP 0 LAST L1 R1950 PLACE CLOSE TO CPU < 25MM
J 0
(-7675 2275);
DISPLAY 0.617021 (-7675 2275);
PAINT WHITE (-7675 2275);
FORCEPROP 2 LAST CDS_LIB pure_quanta_power
J 0
(-7525 2400);
DISPLAY INVISIBLE (-7525 2400);
FORCEPROP 1 LAST COMMENT_BODY TRUE
J 0
(-7500 2500);
DISPLAY 0.574468 (-7500 2500);
PAINT WHITE (-7500 2500);
DISPLAY INVISIBLE (-7500 2500);
FORCEADD QUANTA_TITLE_BLOCK_C..1
(0 0);
FORCEPROP 0 LAST CDS_CON_LAST_MODIFIED Fri Mar 11 14:52:17 2022
J 0
(-1885 15);
DISPLAY INVISIBLE (-1885 15);
FORCEPROP 1 LAST CUSTOM_TXT_CDS <CON_LAST_MODIFIED>
J 0
(-1885 15);
DISPLAY 0.978723 (-1885 15);
FORCEPROP 2 LAST CUSTOM_TXT_CDS <XR_PAGE_TITLE>
J 0
(-7890 5250);
DISPLAY 0.638298 (-7890 5250);
PAINT PINK (-7890 5250);
DISPLAY INVISIBLE (-7890 5250);
FORCEPROP 1 LAST CUSTOM_TXT_CDS <NAME_2>
J 0
(-3175 50);
FORCEPROP 1 LAST CUSTOM_TXT_CDS <NAME_1>
J 0
(-3175 175);
FORCEPROP 1 LAST CUSTOM_TXT_CDS <Q_NUMBER>
J 0
(-1403 103);
DISPLAY 1.212766 (-1403 103);
FORCEPROP 1 LAST CUSTOM_TXT_CDS <Q_PROJ>
J 0
(-2382 102);
DISPLAY 1.212766 (-2382 102);
FORCEPROP 1 LAST CUSTOM_TXT_CDS <Q_REV>
J 0
(-184 103);
DISPLAY 1.212766 (-184 103);
FORCEPROP 1 LAST CUSTOM_TXT_CDS <CON_PAGE_NUM> OF <CON_TOTAL_PAGES>
J 0
(-446 18);
DISPLAY 0.978723 (-446 18);
FORCEPROP 1 LAST Q_DEPT BU9
J 1
(-3763 49);
DISPLAY 1.957447 (-3763 49);
PAINT GREEN (-3763 49);
FORCEPROP 1 LAST Q_TITLE CPU0 DDR CHK
J 0
(-9325 50);
DISPLAY 2.446809 (-9325 50);
PAINT GREEN (-9325 50);
FORCEPROP 1 LAST CDS_LMAN_SYM_OUTLINE -9475,6775,100,-125
J 0
(0 0);
DISPLAY 0.468085 (0 0);
PAINT GREEN (0 0);
DISPLAY INVISIBLE (0 0);
FORCEPROP 2 LAST CDS_LIB pure_quanta
J 0
(0 0);
DISPLAY INVISIBLE (0 0);
FORCEPROP 2 LAST PAGE_BORDER TRUE
J 0
(-7890 5250);
DISPLAY 0.638298 (-7890 5250);
PAINT PINK (-7890 5250);
DISPLAY INVISIBLE (-7890 5250);
FORCEPROP 1 LAST COMMENT_BODY TRUE
J 0
(12 -13);
DISPLAY 0.978723 (12 -13);
PAINT GREEN (12 -13);
DISPLAY INVISIBLE (12 -13);
FORCEPROP 2 LAST CDS_XR_PAGE_TITLE CR-20 : @T6G_MB_LIB.T6G(SCH_1):PAGE20
J 0
(-7890 5250);
DISPLAY 0.638298 (-7890 5250);
PAINT PINK (-7890 5250);
DISPLAY INVISIBLE (-7890 5250);
WIRE 17 -1 (-3100 5425)(-3100 5375);
WIRE 17 -1 (-3100 5475)(-3100 5425);
WIRE 17 -1 (-3100 5375)(-3100 5325);
WIRE 17 -1 (-3100 5325)(-3100 5275);
WIRE 17 -1 (-3100 5525)(-3100 5475);
WIRE 17 -1 (-3100 5625)(-3100 5525);
WIRE 17 -1 (-3100 5275)(-3100 5225);
WIRE 17 -1 (-3100 5225)(-3100 5175);
WIRE 17 -1 (-3100 5675)(-3100 5625);
WIRE 17 -1 (-3100 5725)(-3100 5675);
WIRE 17 -1 (-3100 5075)(-3100 5175);
WIRE 17 -1 (-3100 5025)(-3100 5075);
WIRE 17 -1 (-3100 5775)(-3100 5725);
WIRE 17 -1 (-3100 5825)(-3100 5775);
WIRE 17 -1 (-3100 4975)(-3100 5025);
WIRE 17 -1 (-3100 4925)(-3100 4975);
WIRE 17 -1 (-3100 5875)(-3100 5825);
WIRE 17 -1 (-3100 5925)(-3100 5875);
WIRE 17 -1 (-3100 4925)(-3100 4875);
WIRE 17 -1 (-3100 4875)(-3100 4825);
WIRE 17 -1 (-3100 5975)(-3100 5925);
WIRE 17 -1 (-3100 5975)(-2475 5975);
FORCEPROP 2 LAST SIG_NAME M_K_CPU0_SA_DQ<31:0>
J 2
(-2535 5985);
DISPLAY 0.489362 (-2535 5985);
WIRE 17 -1 (-3100 4825)(-3100 4775);
WIRE 17 -1 (-3100 4775)(-3100 4725);
WIRE 17 -1 (-3100 4725)(-3100 4625);
WIRE 17 -1 (-3100 4625)(-3100 4575);
WIRE 17 -1 (-3100 4575)(-3100 4525);
WIRE 17 -1 (-3100 4525)(-3100 4475);
WIRE 17 -1 (-3100 4425)(-3100 4475);
WIRE 17 -1 (-3100 4375)(-3100 4425);
WIRE 17 -1 (-3100 4325)(-3100 4375);
WIRE 17 -1 (-3100 4275)(-3100 4325);
WIRE 17 -1 (-3100 4175)(-3100 4125);
WIRE 17 -1 (-2475 4175)(-3100 4175);
FORCEPROP 2 LAST SIG_NAME M_K_CPU0_SB_DQ<31:0>
J 2
(-2535 4185);
DISPLAY 0.489362 (-2535 4185);
WIRE 17 -1 (-3100 3125)(-3100 3075);
WIRE 17 -1 (-3100 3125)(-3100 3175);
WIRE 17 -1 (-3100 3075)(-3100 3025);
WIRE 17 -1 (-3100 3025)(-3100 2975);
WIRE 17 -1 (-3100 3175)(-3100 3225);
WIRE 17 -1 (-3100 3225)(-3100 3275);
WIRE 17 -1 (-3100 2975)(-3100 2925);
WIRE 17 -1 (-3100 2925)(-3100 2825);
WIRE 17 -1 (-3100 3275)(-3100 3375);
WIRE 17 -1 (-3100 3425)(-3100 3375);
WIRE 17 -1 (-3100 2825)(-3100 2775);
WIRE 17 -1 (-3100 2775)(-3100 2725);
WIRE 17 -1 (-3100 3475)(-3100 3425);
WIRE 17 -1 (-3100 3525)(-3100 3475);
WIRE 17 -1 (-3100 2725)(-3100 2675);
WIRE 17 -1 (-3100 2625)(-3100 2675);
WIRE 17 -1 (-3100 3575)(-3100 3525);
WIRE 17 -1 (-3100 3625)(-3100 3575);
WIRE 17 -1 (-3100 2575)(-3100 2625);
WIRE 17 -1 (-3100 2525)(-3100 2575);
WIRE 17 -1 (-3100 3675)(-3100 3625);
WIRE 17 -1 (-3100 3725)(-3100 3675);
WIRE 17 -1 (-3100 2475)(-3100 2525);
WIRE 17 -1 (-3100 3825)(-3100 3725);
WIRE 17 -1 (-3100 3875)(-3100 3825);
WIRE 17 -1 (-3100 3925)(-3100 3875);
WIRE 17 -1 (-3100 3975)(-3100 3925);
WIRE 17 -1 (-3100 4025)(-3100 3975);
WIRE 17 -1 (-3100 4075)(-3100 4025);
WIRE 17 -1 (-3100 4125)(-3100 4075);
WIRE 17 -1 (-3100 2375)(-3100 2400);
WIRE 17 -1 (-3100 2375)(-3100 2325);
WIRE 17 -1 (-3100 2400)(-2600 2400);
FORCEPROP 2 LAST SIG_NAME M_K_CPU0_SA_CB<7:0>
J 2
(-2600 2410);
DISPLAY 0.489362 (-2600 2410);
WIRE 17 -1 (-3100 2275)(-3100 2325);
WIRE 17 -1 (-3100 2275)(-3100 2225);
WIRE 17 -1 (-3100 2175)(-3100 2225);
WIRE 17 -1 (-3100 2125)(-3100 2175);
WIRE 17 -1 (-3100 2075)(-3100 2125);
WIRE 17 -1 (-3100 2025)(-3100 2075);
WIRE 17 -1 (-3100 1925)(-3100 1875);
WIRE 17 -1 (-3100 1925)(-3100 1950);
WIRE 17 -1 (-3100 1825)(-3100 1875);
WIRE 17 -1 (-3100 1825)(-3100 1775);
WIRE 17 -1 (-3100 1950)(-2600 1950);
FORCEPROP 2 LAST SIG_NAME M_K_CPU0_SB_CB<7:0>
J 2
(-2600 1960);
DISPLAY 0.489362 (-2600 1960);
WIRE 17 -1 (-3100 1725)(-3100 1775);
WIRE 17 -1 (-3100 1675)(-3100 1725);
WIRE 17 -1 (-3100 1625)(-3100 1675);
WIRE 17 -1 (-3100 1575)(-3100 1625);
WIRE 17 -1 (-5625 5975)(-5625 5875);
WIRE 17 -1 (-5625 5975)(-6425 5975);
FORCEPROP 2 LAST SIG_NAME M_K_CPU0_SA_DQS_DP<9:0>
J 2
(-5860 5985);
DISPLAY 0.489362 (-5860 5985);
WIRE 17 -1 (-5625 5875)(-5625 5775);
WIRE 17 -1 (-5625 5775)(-5625 5675);
WIRE 17 -1 (-5625 5675)(-5625 5575);
WIRE 17 -1 (-5625 5475)(-5625 5575);
WIRE 17 -1 (-5625 5375)(-5625 5475);
WIRE 17 -1 (-5625 5275)(-5625 5375);
WIRE 17 -1 (-5625 5275)(-5625 5175);
WIRE 17 -1 (-5625 5175)(-5625 5075);
WIRE 17 -1 (-5825 5925)(-5825 5825);
FORCEPROP 2 LAST SIG_NAME M_K_CPU0_SA_DQS_DN<9:0>
J 2
(-5860 5935);
DISPLAY 0.489362 (-5860 5935);
WIRE 17 -1 (-5825 5725)(-5825 5625);
WIRE 17 -1 (-5825 5825)(-5825 5725);
WIRE 17 -1 (-5825 5625)(-5825 5525);
WIRE 17 -1 (-5825 5425)(-5825 5525);
WIRE 17 -1 (-5825 5325)(-5825 5425);
WIRE 17 -1 (-5825 5225)(-5825 5325);
WIRE 17 -1 (-5825 5225)(-5825 5125);
WIRE 17 -1 (-5825 5125)(-5825 5025);
WIRE 17 -1 (-5625 4725)(-5625 4625);
WIRE 17 -1 (-5625 4825)(-5625 4725);
WIRE 17 -1 (-5625 4625)(-5625 4525);
WIRE 17 -1 (-5625 4425)(-5625 4525);
WIRE 17 -1 (-5625 4925)(-5625 4825);
WIRE 17 -1 (-5625 4925)(-6425 4925);
FORCEPROP 2 LAST SIG_NAME M_K_CPU0_SB_DQS_DP<9:0>
J 2
(-5860 4935);
DISPLAY 0.489362 (-5860 4935);
WIRE 17 -1 (-5625 4325)(-5625 4425);
WIRE 17 -1 (-5625 4225)(-5625 4325);
WIRE 17 -1 (-5625 4225)(-5625 4125);
WIRE 17 -1 (-5625 4125)(-5625 4025);
WIRE 17 -1 (-5825 4275)(-5825 4375);
WIRE 17 -1 (-5825 4175)(-5825 4275);
WIRE 17 -1 (-5825 4375)(-5825 4475);
WIRE 17 -1 (-5825 4575)(-5825 4475);
WIRE 17 -1 (-5825 4175)(-5825 4075);
WIRE 17 -1 (-5825 4075)(-5825 3975);
WIRE 17 -1 (-5825 4675)(-5825 4575);
WIRE 17 -1 (-5825 4775)(-5825 4675);
WIRE 17 -1 (-5825 4875)(-5825 4775);
FORCEPROP 2 LAST SIG_NAME M_K_CPU0_SB_DQS_DN<9:0>
J 2
(-5860 4885);
DISPLAY 0.489362 (-5860 4885);
WIRE 17 -1 (-5825 3375)(-5825 3425);
WIRE 17 -1 (-5825 3325)(-5825 3375);
WIRE 17 -1 (-5825 3425)(-6325 3425);
FORCEPROP 2 LAST SIG_NAME M_K_CPU0_SB_CA<6:0>
J 0
(-6325 3435);
DISPLAY 0.489362 (-6325 3435);
WIRE 17 -1 (-5825 3775)(-5825 3825);
WIRE 17 -1 (-5825 3725)(-5825 3775);
WIRE 17 -1 (-5825 3825)(-6325 3825);
FORCEPROP 2 LAST SIG_NAME M_K_CPU0_SA_CA<6:0>
J 0
(-6325 3835);
DISPLAY 0.489362 (-6325 3835);
WIRE 17 -1 (-5825 3275)(-5825 3325);
WIRE 17 -1 (-5825 3675)(-5825 3725);
WIRE 17 -1 (-5825 3625)(-5825 3675);
WIRE 17 -1 (-5825 3575)(-5825 3625);
WIRE 17 -1 (-5825 3525)(-5825 3575);
WIRE 17 -1 (-5825 3225)(-5825 3275);
WIRE 17 -1 (-5825 3175)(-5825 3225);
WIRE 17 -1 (-5825 3125)(-5825 3175);
WIRE 17 -1 (-5825 5925)(-6425 5925);
WIRE 17 -1 (-5825 4875)(-6425 4875);
WIRE 16 -1 (-7525 2100)(-6800 2100);
FORCEPROP 2 LAST SIG_NAME M_K_CPU0_ALERT_N
J 0
(-7485 2110);
DISPLAY 0.489362 (-7485 2110);
WIRE 16 -1 (-6325 1150)(-5225 1150);
FORCEPROP 2 LAST SIG_NAME TP_M_K_CPU0_SA_TEST39K
J 0
(-6310 1160);
DISPLAY 0.489362 (-6310 1160);
FORCEPROP 2 LASTPROP $XRERR UNIQUE?
J 0
(-6565 1150);
DISPLAY 0.638298 (-6565 1150);
PAINT MONO (-6565 1150);
DISPLAY INVISIBLE (-6565 1150);
WIRE 16 -1 (-6600 2100)(-5225 2100);
FORCEPROP 2 LAST SIG_NAME M_K_CPU0_ALERT_R_N
J 0
(-6310 2110);
DISPLAY 0.489362 (-6310 2110);
FORCEPROP 2 LASTPROP $XRERR UNIQUE?
J 0
(-6550 2110);
DISPLAY 0.638298 (-6550 2110);
PAINT MONO (-6550 2110);
DISPLAY INVISIBLE (-6550 2110);
WIRE 16 -1 (-6325 2950)(-5225 2950);
FORCEPROP 2 LAST SIG_NAME M_K_CPU0_CLK_DP<0>
J 0
(-6325 2960);
DISPLAY 0.489362 (-6325 2960);
WIRE 16 -1 (-6325 2900)(-5225 2900);
FORCEPROP 2 LAST SIG_NAME M_K_CPU0_CLK_DN<0>
J 0
(-6325 2910);
DISPLAY 0.489362 (-6325 2910);
WIRE 16 -1 (-6325 2800)(-5225 2800);
FORCEPROP 2 LAST SIG_NAME M_K_CPU0_SA_CS_N<0>
J 0
(-6325 2810);
DISPLAY 0.489362 (-6325 2810);
WIRE 16 -1 (-6325 2650)(-5225 2650);
FORCEPROP 2 LAST SIG_NAME M_K_CPU0_SA_RSP<0>
J 0
(-6325 2660);
DISPLAY 0.489362 (-6325 2660);
WIRE 16 -1 (-6325 2750)(-5225 2750);
FORCEPROP 2 LAST SIG_NAME M_K_CPU0_SA_CS_N<1>
J 0
(-6325 2760);
DISPLAY 0.489362 (-6325 2760);
WIRE 16 -1 (-6325 2550)(-5225 2550);
FORCEPROP 2 LAST SIG_NAME M_K_CPU0_SA_PAR
J 0
(-6325 2560);
DISPLAY 0.489362 (-6325 2560);
WIRE 16 -1 (-6325 2450)(-5225 2450);
FORCEPROP 2 LAST SIG_NAME M_K_CPU0_SB_CS_N<0>
J 0
(-6325 2460);
DISPLAY 0.489362 (-6325 2460);
WIRE 16 -1 (-6325 2400)(-5225 2400);
FORCEPROP 2 LAST SIG_NAME M_K_CPU0_SB_CS_N<1>
J 0
(-6325 2410);
DISPLAY 0.489362 (-6325 2410);
WIRE 16 -1 (-6325 2300)(-5225 2300);
FORCEPROP 2 LAST SIG_NAME M_K_CPU0_SB_RSP<0>
J 0
(-6325 2310);
DISPLAY 0.489362 (-6325 2310);
WIRE 16 -1 (-6325 2200)(-5225 2200);
FORCEPROP 2 LAST SIG_NAME M_K_CPU0_SB_PAR
J 0
(-6325 2210);
DISPLAY 0.489362 (-6325 2210);
WIRE 16 -1 (-6325 2000)(-5225 2000);
FORCEPROP 2 LAST SIG_NAME M_K_CPU0_RESET_N
J 0
(-6325 2010);
DISPLAY 0.489362 (-6325 2010);
WIRE 16 -1 (-5725 3800)(-5225 3800);
WIRE 16 -1 (-5725 3100)(-5225 3100);
WIRE 16 -1 (-5725 3500)(-5225 3500);
WIRE 16 -1 (-5725 3150)(-5225 3150);
WIRE 16 -1 (-5725 3550)(-5225 3550);
WIRE 16 -1 (-5725 3200)(-5225 3200);
WIRE 16 -1 (-5725 3600)(-5225 3600);
WIRE 16 -1 (-5725 3250)(-5225 3250);
WIRE 16 -1 (-5725 3950)(-5225 3950);
WIRE 16 -1 (-5725 3650)(-5225 3650);
WIRE 16 -1 (-5725 3300)(-5225 3300);
WIRE 16 -1 (-5725 4050)(-5225 4050);
WIRE 16 -1 (-5725 3700)(-5225 3700);
WIRE 16 -1 (-5725 3350)(-5225 3350);
WIRE 16 -1 (-5725 3750)(-5225 3750);
WIRE 16 -1 (-5725 3400)(-5225 3400);
WIRE 16 -1 (-5525 4000)(-5225 4000);
WIRE 16 -1 (-5725 4350)(-5225 4350);
WIRE 16 -1 (-5725 4450)(-5225 4450);
WIRE 16 -1 (-5725 5000)(-5225 5000);
WIRE 16 -1 (-5725 4550)(-5225 4550);
WIRE 16 -1 (-5725 5100)(-5225 5100);
WIRE 16 -1 (-5725 4650)(-5225 4650);
WIRE 16 -1 (-5725 4750)(-5225 4750);
WIRE 16 -1 (-5725 4850)(-5225 4850);
WIRE 16 -1 (-5725 4150)(-5225 4150);
WIRE 16 -1 (-5725 4250)(-5225 4250);
WIRE 16 -1 (-5525 4100)(-5225 4100);
WIRE 16 -1 (-5525 4200)(-5225 4200);
WIRE 16 -1 (-5525 4300)(-5225 4300);
WIRE 16 -1 (-5525 4400)(-5225 4400);
WIRE 16 -1 (-5525 4500)(-5225 4500);
WIRE 16 -1 (-5525 4600)(-5225 4600);
WIRE 16 -1 (-5525 4800)(-5225 4800);
WIRE 16 -1 (-5525 4900)(-5225 4900);
WIRE 16 -1 (-5525 5050)(-5225 5050);
WIRE 16 -1 (-5525 4700)(-5225 4700);
WIRE 16 -1 (-5725 5200)(-5225 5200);
WIRE 16 -1 (-5725 5300)(-5225 5300);
WIRE 16 -1 (-5725 5400)(-5225 5400);
WIRE 16 -1 (-5725 5500)(-5225 5500);
WIRE 16 -1 (-5725 5600)(-5225 5600);
WIRE 16 -1 (-5725 5700)(-5225 5700);
WIRE 16 -1 (-5725 5800)(-5225 5800);
WIRE 16 -1 (-5725 5900)(-5225 5900);
WIRE 16 -1 (-5525 5250)(-5225 5250);
WIRE 16 -1 (-5525 5350)(-5225 5350);
WIRE 16 -1 (-5525 5450)(-5225 5450);
WIRE 16 -1 (-5525 5550)(-5225 5550);
WIRE 16 -1 (-5525 5150)(-5225 5150);
WIRE 16 -1 (-5525 5650)(-5225 5650);
WIRE 16 -1 (-5525 5750)(-5225 5750);
WIRE 16 -1 (-5525 5850)(-5225 5850);
WIRE 16 -1 (-5525 5950)(-5225 5950);
WIRE 16 -1 (-3625 1550)(-3200 1550);
WIRE 16 -1 (-3625 1600)(-3200 1600);
WIRE 16 -1 (-3625 1650)(-3200 1650);
WIRE 16 -1 (-3625 1700)(-3200 1700);
WIRE 16 -1 (-3625 1750)(-3200 1750);
WIRE 16 -1 (-3625 1800)(-3200 1800);
WIRE 16 -1 (-3625 2000)(-3200 2000);
WIRE 16 -1 (-3625 1850)(-3200 1850);
WIRE 16 -1 (-3625 1900)(-3200 1900);
WIRE 16 -1 (-3625 2550)(-3200 2550);
WIRE 16 -1 (-3625 2600)(-3200 2600);
WIRE 16 -1 (-3625 2650)(-3200 2650);
WIRE 16 -1 (-3625 2700)(-3200 2700);
WIRE 16 -1 (-3625 2750)(-3200 2750);
WIRE 16 -1 (-3625 2800)(-3200 2800);
WIRE 16 -1 (-3625 2900)(-3200 2900);
WIRE 16 -1 (-3625 2950)(-3200 2950);
WIRE 16 -1 (-3625 3000)(-3200 3000);
WIRE 16 -1 (-3625 2050)(-3200 2050);
WIRE 16 -1 (-3625 3050)(-3200 3050);
WIRE 16 -1 (-3625 2450)(-3200 2450);
WIRE 16 -1 (-3625 2100)(-3200 2100);
WIRE 16 -1 (-3625 2500)(-3200 2500);
WIRE 16 -1 (-3625 2150)(-3200 2150);
WIRE 16 -1 (-3625 2200)(-3200 2200);
WIRE 16 -1 (-3625 2250)(-3200 2250);
WIRE 16 -1 (-3625 2300)(-3200 2300);
WIRE 16 -1 (-3625 2350)(-3200 2350);
WIRE 16 -1 (-3625 3650)(-3200 3650);
WIRE 16 -1 (-3625 3150)(-3200 3150);
WIRE 16 -1 (-3625 3700)(-3200 3700);
WIRE 16 -1 (-3625 3200)(-3200 3200);
WIRE 16 -1 (-3625 3800)(-3200 3800);
WIRE 16 -1 (-3625 3250)(-3200 3250);
WIRE 16 -1 (-3625 3850)(-3200 3850);
WIRE 16 -1 (-3625 3350)(-3200 3350);
WIRE 16 -1 (-3625 3900)(-3200 3900);
WIRE 16 -1 (-3625 3400)(-3200 3400);
WIRE 16 -1 (-3625 3950)(-3200 3950);
WIRE 16 -1 (-3625 3450)(-3200 3450);
WIRE 16 -1 (-3625 4000)(-3200 4000);
WIRE 16 -1 (-3625 3500)(-3200 3500);
WIRE 16 -1 (-3625 4050)(-3200 4050);
WIRE 16 -1 (-3625 3550)(-3200 3550);
WIRE 16 -1 (-3625 3600)(-3200 3600);
WIRE 16 -1 (-3625 3100)(-3200 3100);
WIRE 16 -1 (-3625 4900)(-3200 4900);
WIRE 16 -1 (-3625 4950)(-3200 4950);
WIRE 16 -1 (-3625 4350)(-3200 4350);
WIRE 16 -1 (-3625 5000)(-3200 5000);
WIRE 16 -1 (-3625 4400)(-3200 4400);
WIRE 16 -1 (-3625 5050)(-3200 5050);
WIRE 16 -1 (-3625 4450)(-3200 4450);
WIRE 16 -1 (-3625 4100)(-3200 4100);
WIRE 16 -1 (-3625 4500)(-3200 4500);
WIRE 16 -1 (-3625 4150)(-3200 4150);
WIRE 16 -1 (-3625 4550)(-3200 4550);
WIRE 16 -1 (-3625 4600)(-3200 4600);
WIRE 16 -1 (-3625 4700)(-3200 4700);
WIRE 16 -1 (-3625 4750)(-3200 4750);
WIRE 16 -1 (-3625 4800)(-3200 4800);
WIRE 16 -1 (-3625 4850)(-3200 4850);
WIRE 16 -1 (-3625 4250)(-3200 4250);
WIRE 16 -1 (-3625 4300)(-3200 4300);
WIRE 16 -1 (-3625 5450)(-3200 5450);
WIRE 16 -1 (-3625 5500)(-3200 5500);
WIRE 16 -1 (-3625 5600)(-3200 5600);
WIRE 16 -1 (-3625 5650)(-3200 5650);
WIRE 16 -1 (-3625 5700)(-3200 5700);
WIRE 16 -1 (-3625 5750)(-3200 5750);
WIRE 16 -1 (-3625 5800)(-3200 5800);
WIRE 16 -1 (-3625 5850)(-3200 5850);
WIRE 16 -1 (-3625 5900)(-3200 5900);
WIRE 16 -1 (-3625 5150)(-3200 5150);
WIRE 16 -1 (-3625 5950)(-3200 5950);
WIRE 16 -1 (-3625 5200)(-3200 5200);
WIRE 16 -1 (-3625 5250)(-3200 5250);
WIRE 16 -1 (-3625 5300)(-3200 5300);
WIRE 16 -1 (-3625 5350)(-3200 5350);
WIRE 16 -1 (-3625 5400)(-3200 5400);
QUIT
